(kicad_sch
	(version 20250114)
	(generator "eeschema")
	(generator_version "9.0")
	(paper "A3")
	(title_block
		(title "Antmicro Baseboard for Jetson AGX Thor")
		(date "2026-02-17")
		(rev "1.1.0")
		(company "Antmicro Ltd")
		(comment 1 "www.antmicro.com")
	)
	(text "NOTE:\nConfigurations shown \nin USB7252CT-I/KDX\ndatasheet table 3-5. \nCurrently set to \nconfiguration 4 (SMBus/I2C)"
		(exclude_from_sim no)
		(at 19.812 163.83 0)
		(effects
			(font
				(size 1.27 1.27)
			)
			(justify left)
		)
	)
	(text "USB PORT 4\n\n"
		(exclude_from_sim no)
		(at 368.046 178.308 0)
		(effects
			(font
				(size 1.27 1.27)
				(thickness 0.254)
				(bold yes)
			)
		)
	)
	(text "USB hub\n"
		(exclude_from_sim no)
		(at 197.358 25.908 0)
		(effects
			(font
				(size 2.54 2.54)
				(thickness 0.508)
				(bold yes)
			)
		)
	)
	(text "Note: \nTX/RX cross is intentional\n(it normally happens in USB cable)"
		(exclude_from_sim no)
		(at 68.326 93.98 0)
		(effects
			(font
				(size 1.27 1.27)
			)
			(justify left)
		)
	)
	(text "VCONN Switches"
		(exclude_from_sim no)
		(at 190.5 214.122 0)
		(effects
			(font
				(size 2.54 2.54)
				(thickness 0.508)
				(bold yes)
			)
		)
	)
	(text "USB PORT 3\n\n"
		(exclude_from_sim no)
		(at 368.046 56.388 0)
		(effects
			(font
				(size 1.27 1.27)
				(thickness 0.254)
				(bold yes)
			)
		)
	)
	(text "USB Hub flash\n"
		(exclude_from_sim no)
		(at 33.274 217.932 0)
		(effects
			(font
				(size 2.54 2.54)
				(thickness 0.508)
				(bold yes)
			)
		)
	)
	(text "Alt modes:\n\n/CFG_BC_EN\n/CFG_NON_REM"
		(exclude_from_sim no)
		(at 199.136 174.752 0)
		(effects
			(font
				(size 1.27 1.27)
			)
			(justify left)
		)
	)
	(text "NOTE:\nConfigurations shown in USB7252CT-I/KDX\ndocumentaion table 3-2 and 3-3. \nIn this case it is set to:\n- All ports removable\n- Battery charging not enabled on any port"
		(exclude_from_sim no)
		(at 214.884 148.59 0)
		(effects
			(font
				(size 1.27 1.27)
			)
			(justify left)
		)
	)
	(junction
		(at 38.1 67.31)
		(diameter 0)
		(color 0 0 0 0)
	)
	(junction
		(at 339.09 213.36)
		(diameter 0)
		(color 0 0 0 0)
	)
	(junction
		(at 347.98 31.75)
		(diameter 0)
		(color 0 0 0 0)
	)
	(junction
		(at 99.06 41.91)
		(diameter 0)
		(color 0 0 0 0)
	)
	(junction
		(at 58.42 67.31)
		(diameter 0)
		(color 0 0 0 0)
	)
	(junction
		(at 322.58 226.06)
		(diameter 0)
		(color 0 0 0 0)
	)
	(junction
		(at 38.1 59.69)
		(diameter 0)
		(color 0 0 0 0)
	)
	(junction
		(at 317.5 63.5)
		(diameter 0)
		(color 0 0 0 0)
	)
	(junction
		(at 58.42 41.91)
		(diameter 0)
		(color 0 0 0 0)
	)
	(junction
		(at 320.04 68.58)
		(diameter 0)
		(color 0 0 0 0)
	)
	(junction
		(at 341.63 88.9)
		(diameter 0)
		(color 0 0 0 0)
	)
	(junction
		(at 87.63 226.06)
		(diameter 0)
		(color 0 0 0 0)
	)
	(junction
		(at 322.58 104.14)
		(diameter 0)
		(color 0 0 0 0)
	)
	(junction
		(at 151.13 265.43)
		(diameter 0)
		(color 0 0 0 0)
	)
	(junction
		(at 226.06 241.3)
		(diameter 0)
		(color 0 0 0 0)
	)
	(junction
		(at 323.85 190.5)
		(diameter 0)
		(color 0 0 0 0)
	)
	(junction
		(at 337.82 41.91)
		(diameter 0)
		(color 0 0 0 0)
	)
	(junction
		(at 317.5 96.52)
		(diameter 0)
		(color 0 0 0 0)
	)
	(junction
		(at 68.58 49.53)
		(diameter 0)
		(color 0 0 0 0)
	)
	(junction
		(at 321.31 193.04)
		(diameter 0)
		(color 0 0 0 0)
	)
	(junction
		(at 350.52 121.92)
		(diameter 0)
		(color 0 0 0 0)
	)
	(junction
		(at 88.9 59.69)
		(diameter 0)
		(color 0 0 0 0)
	)
	(junction
		(at 208.28 63.5)
		(diameter 0)
		(color 0 0 0 0)
	)
	(junction
		(at 336.55 163.83)
		(diameter 0)
		(color 0 0 0 0)
	)
	(junction
		(at 350.52 243.84)
		(diameter 0)
		(color 0 0 0 0)
	)
	(junction
		(at 88.9 49.53)
		(diameter 0)
		(color 0 0 0 0)
	)
	(junction
		(at 207.01 231.14)
		(diameter 0)
		(color 0 0 0 0)
	)
	(junction
		(at 236.22 165.1)
		(diameter 0)
		(color 0 0 0 0)
	)
	(junction
		(at 27.94 95.25)
		(diameter 0)
		(color 0 0 0 0)
	)
	(junction
		(at 99.06 49.53)
		(diameter 0)
		(color 0 0 0 0)
	)
	(junction
		(at 317.5 36.83)
		(diameter 0)
		(color 0 0 0 0)
	)
	(junction
		(at 124.46 186.69)
		(diameter 0)
		(color 0 0 0 0)
	)
	(junction
		(at 361.95 31.75)
		(diameter 0)
		(color 0 0 0 0)
	)
	(junction
		(at 369.57 153.67)
		(diameter 0)
		(color 0 0 0 0)
	)
	(junction
		(at 83.82 243.84)
		(diameter 0)
		(color 0 0 0 0)
	)
	(junction
		(at 201.93 151.13)
		(diameter 0)
		(color 0 0 0 0)
	)
	(junction
		(at 341.63 210.82)
		(diameter 0)
		(color 0 0 0 0)
	)
	(junction
		(at 88.9 67.31)
		(diameter 0)
		(color 0 0 0 0)
	)
	(junction
		(at 316.23 182.88)
		(diameter 0)
		(color 0 0 0 0)
	)
	(junction
		(at 88.9 41.91)
		(diameter 0)
		(color 0 0 0 0)
	)
	(junction
		(at 167.64 241.3)
		(diameter 0)
		(color 0 0 0 0)
	)
	(junction
		(at 109.22 59.69)
		(diameter 0)
		(color 0 0 0 0)
	)
	(junction
		(at 100.33 163.83)
		(diameter 0)
		(color 0 0 0 0)
	)
	(junction
		(at 48.26 49.53)
		(diameter 0)
		(color 0 0 0 0)
	)
	(junction
		(at 316.23 158.75)
		(diameter 0)
		(color 0 0 0 0)
	)
	(junction
		(at 209.55 241.3)
		(diameter 0)
		(color 0 0 0 0)
	)
	(junction
		(at 74.93 226.06)
		(diameter 0)
		(color 0 0 0 0)
	)
	(junction
		(at 92.71 163.83)
		(diameter 0)
		(color 0 0 0 0)
	)
	(junction
		(at 151.13 241.3)
		(diameter 0)
		(color 0 0 0 0)
	)
	(junction
		(at 209.55 265.43)
		(diameter 0)
		(color 0 0 0 0)
	)
	(junction
		(at 370.84 31.75)
		(diameter 0)
		(color 0 0 0 0)
	)
	(junction
		(at 336.55 203.2)
		(diameter 0)
		(color 0 0 0 0)
	)
	(junction
		(at 199.39 146.05)
		(diameter 0)
		(color 0 0 0 0)
	)
	(junction
		(at 318.77 185.42)
		(diameter 0)
		(color 0 0 0 0)
	)
	(junction
		(at 148.59 255.27)
		(diameter 0)
		(color 0 0 0 0)
	)
	(junction
		(at 347.98 71.12)
		(diameter 0)
		(color 0 0 0 0)
	)
	(junction
		(at 307.34 143.51)
		(diameter 0)
		(color 0 0 0 0)
	)
	(junction
		(at 360.68 153.67)
		(diameter 0)
		(color 0 0 0 0)
	)
	(junction
		(at 350.52 190.5)
		(diameter 0)
		(color 0 0 0 0)
	)
	(junction
		(at 58.42 49.53)
		(diameter 0)
		(color 0 0 0 0)
	)
	(junction
		(at 314.96 99.06)
		(diameter 0)
		(color 0 0 0 0)
	)
	(junction
		(at 350.52 68.58)
		(diameter 0)
		(color 0 0 0 0)
	)
	(junction
		(at 373.38 153.67)
		(diameter 0)
		(color 0 0 0 0)
	)
	(junction
		(at 99.06 67.31)
		(diameter 0)
		(color 0 0 0 0)
	)
	(junction
		(at 38.1 41.91)
		(diameter 0)
		(color 0 0 0 0)
	)
	(junction
		(at 17.78 59.69)
		(diameter 0)
		(color 0 0 0 0)
	)
	(junction
		(at 167.64 260.35)
		(diameter 0)
		(color 0 0 0 0)
	)
	(junction
		(at 322.58 71.12)
		(diameter 0)
		(color 0 0 0 0)
	)
	(junction
		(at 78.74 67.31)
		(diameter 0)
		(color 0 0 0 0)
	)
	(junction
		(at 17.78 49.53)
		(diameter 0)
		(color 0 0 0 0)
	)
	(junction
		(at 336.55 81.28)
		(diameter 0)
		(color 0 0 0 0)
	)
	(junction
		(at 78.74 251.46)
		(diameter 0)
		(color 0 0 0 0)
	)
	(junction
		(at 226.06 260.35)
		(diameter 0)
		(color 0 0 0 0)
	)
	(junction
		(at 334.01 205.74)
		(diameter 0)
		(color 0 0 0 0)
	)
	(junction
		(at 48.26 67.31)
		(diameter 0)
		(color 0 0 0 0)
	)
	(junction
		(at 334.01 83.82)
		(diameter 0)
		(color 0 0 0 0)
	)
	(junction
		(at 374.65 31.75)
		(diameter 0)
		(color 0 0 0 0)
	)
	(junction
		(at 351.79 31.75)
		(diameter 0)
		(color 0 0 0 0)
	)
	(junction
		(at 226.06 236.22)
		(diameter 0)
		(color 0 0 0 0)
	)
	(junction
		(at 320.04 106.68)
		(diameter 0)
		(color 0 0 0 0)
	)
	(junction
		(at 68.58 67.31)
		(diameter 0)
		(color 0 0 0 0)
	)
	(junction
		(at 58.42 59.69)
		(diameter 0)
		(color 0 0 0 0)
	)
	(junction
		(at 29.21 41.91)
		(diameter 0)
		(color 0 0 0 0)
	)
	(junction
		(at 99.06 59.69)
		(diameter 0)
		(color 0 0 0 0)
	)
	(junction
		(at 68.58 41.91)
		(diameter 0)
		(color 0 0 0 0)
	)
	(junction
		(at 29.21 49.53)
		(diameter 0)
		(color 0 0 0 0)
	)
	(junction
		(at 68.58 59.69)
		(diameter 0)
		(color 0 0 0 0)
	)
	(junction
		(at 226.06 265.43)
		(diameter 0)
		(color 0 0 0 0)
	)
	(junction
		(at 17.78 41.91)
		(diameter 0)
		(color 0 0 0 0)
	)
	(junction
		(at 27.94 185.42)
		(diameter 0)
		(color 0 0 0 0)
	)
	(junction
		(at 201.93 158.75)
		(diameter 0)
		(color 0 0 0 0)
	)
	(junction
		(at 38.1 49.53)
		(diameter 0)
		(color 0 0 0 0)
	)
	(junction
		(at 228.6 179.07)
		(diameter 0)
		(color 0 0 0 0)
	)
	(junction
		(at 167.64 236.22)
		(diameter 0)
		(color 0 0 0 0)
	)
	(junction
		(at 76.2 248.92)
		(diameter 0)
		(color 0 0 0 0)
	)
	(junction
		(at 236.22 176.53)
		(diameter 0)
		(color 0 0 0 0)
	)
	(junction
		(at 27.94 128.27)
		(diameter 0)
		(color 0 0 0 0)
	)
	(junction
		(at 317.5 218.44)
		(diameter 0)
		(color 0 0 0 0)
	)
	(junction
		(at 320.04 228.6)
		(diameter 0)
		(color 0 0 0 0)
	)
	(junction
		(at 347.98 193.04)
		(diameter 0)
		(color 0 0 0 0)
	)
	(junction
		(at 48.26 41.91)
		(diameter 0)
		(color 0 0 0 0)
	)
	(junction
		(at 339.09 91.44)
		(diameter 0)
		(color 0 0 0 0)
	)
	(junction
		(at 71.12 148.59)
		(diameter 0)
		(color 0 0 0 0)
	)
	(junction
		(at 148.59 231.14)
		(diameter 0)
		(color 0 0 0 0)
	)
	(junction
		(at 81.28 246.38)
		(diameter 0)
		(color 0 0 0 0)
	)
	(junction
		(at 109.22 41.91)
		(diameter 0)
		(color 0 0 0 0)
	)
	(junction
		(at 314.96 60.96)
		(diameter 0)
		(color 0 0 0 0)
	)
	(junction
		(at 80.01 148.59)
		(diameter 0)
		(color 0 0 0 0)
	)
	(junction
		(at 207.01 255.27)
		(diameter 0)
		(color 0 0 0 0)
	)
	(junction
		(at 167.64 265.43)
		(diameter 0)
		(color 0 0 0 0)
	)
	(junction
		(at 350.52 153.67)
		(diameter 0)
		(color 0 0 0 0)
	)
	(junction
		(at 48.26 59.69)
		(diameter 0)
		(color 0 0 0 0)
	)
	(junction
		(at 78.74 49.53)
		(diameter 0)
		(color 0 0 0 0)
	)
	(junction
		(at 314.96 220.98)
		(diameter 0)
		(color 0 0 0 0)
	)
	(junction
		(at 78.74 41.91)
		(diameter 0)
		(color 0 0 0 0)
	)
	(junction
		(at 346.71 153.67)
		(diameter 0)
		(color 0 0 0 0)
	)
	(junction
		(at 78.74 59.69)
		(diameter 0)
		(color 0 0 0 0)
	)
	(junction
		(at 201.93 148.59)
		(diameter 0)
		(color 0 0 0 0)
	)
	(junction
		(at 208.28 101.6)
		(diameter 0)
		(color 0 0 0 0)
	)
	(junction
		(at 308.61 21.59)
		(diameter 0)
		(color 0 0 0 0)
	)
	(junction
		(at 17.78 67.31)
		(diameter 0)
		(color 0 0 0 0)
	)
	(no_connect
		(at 127 149.86)
	)
	(no_connect
		(at 127 106.68)
	)
	(no_connect
		(at 127 142.24)
	)
	(no_connect
		(at 127 152.4)
	)
	(no_connect
		(at 127 124.46)
	)
	(no_connect
		(at 351.79 111.76)
	)
	(no_connect
		(at 351.79 233.68)
	)
	(no_connect
		(at 127 104.14)
	)
	(no_connect
		(at 351.79 236.22)
	)
	(no_connect
		(at 127 147.32)
	)
	(no_connect
		(at 182.88 138.43)
	)
	(no_connect
		(at 127 157.48)
	)
	(no_connect
		(at 127 134.62)
	)
	(no_connect
		(at 127 109.22)
	)
	(no_connect
		(at 182.88 140.97)
	)
	(no_connect
		(at 127 144.78)
	)
	(no_connect
		(at 351.79 114.3)
	)
	(no_connect
		(at 127 111.76)
	)
	(no_connect
		(at 127 119.38)
	)
	(bus_entry
		(at 72.39 78.74)
		(size 1.27 1.27)
		(stroke
			(width 0)
			(type default)
		)
	)
	(bus_entry
		(at 53.34 275.59)
		(size 1.27 1.27)
		(stroke
			(width 0)
			(type default)
		)
	)
	(bus_entry
		(at 100.33 135.89)
		(size 1.27 1.27)
		(stroke
			(width 0)
			(type default)
		)
	)
	(bus_entry
		(at 53.34 278.13)
		(size 1.27 1.27)
		(stroke
			(width 0)
			(type default)
		)
	)
	(bus_entry
		(at 72.39 73.66)
		(size 1.27 1.27)
		(stroke
			(width 0)
			(type default)
		)
	)
	(bus_entry
		(at 101.6 139.7)
		(size -1.27 -1.27)
		(stroke
			(width 0)
			(type default)
		)
	)
	(bus_entry
		(at 100.33 138.43)
		(size 1.27 1.27)
		(stroke
			(width 0)
			(type default)
		)
	)
	(bus_entry
		(at 72.39 76.2)
		(size 1.27 1.27)
		(stroke
			(width 0)
			(type default)
		)
	)
	(bus_entry
		(at 101.6 137.16)
		(size -1.27 -1.27)
		(stroke
			(width 0)
			(type default)
		)
	)
	(bus_entry
		(at 72.39 83.82)
		(size 1.27 1.27)
		(stroke
			(width 0)
			(type default)
		)
	)
	(bus_entry
		(at 73.66 85.09)
		(size -1.27 -1.27)
		(stroke
			(width 0)
			(type default)
		)
	)
	(bus_entry
		(at 53.34 273.05)
		(size 1.27 1.27)
		(stroke
			(width 0)
			(type default)
		)
	)
	(bus_entry
		(at 72.39 81.28)
		(size 1.27 1.27)
		(stroke
			(width 0)
			(type default)
		)
	)
	(bus_entry
		(at 72.39 86.36)
		(size 1.27 1.27)
		(stroke
			(width 0)
			(type default)
		)
	)
	(bus_entry
		(at 53.34 270.51)
		(size 1.27 1.27)
		(stroke
			(width 0)
			(type default)
		)
	)
	(bus_entry
		(at 73.66 87.63)
		(size -1.27 -1.27)
		(stroke
			(width 0)
			(type default)
		)
	)
	(wire
		(pts
			(xy 114.3 132.08) (xy 127 132.08)
		)
		(stroke
			(width 0)
			(type default)
		)
	)
	(wire
		(pts
			(xy 104.14 82.55) (xy 127 82.55)
		)
		(stroke
			(width 0)
			(type default)
		)
	)
	(wire
		(pts
			(xy 201.93 158.75) (xy 201.93 151.13)
		)
		(stroke
			(width 0)
			(type default)
		)
	)
	(wire
		(pts
			(xy 17.78 59.69) (xy 38.1 59.69)
		)
		(stroke
			(width 0)
			(type default)
		)
	)
	(wire
		(pts
			(xy 351.79 31.75) (xy 361.95 31.75)
		)
		(stroke
			(width 0)
			(type default)
		)
	)
	(wire
		(pts
			(xy 228.6 171.45) (xy 228.6 179.07)
		)
		(stroke
			(width 0)
			(type default)
		)
	)
	(wire
		(pts
			(xy 317.5 34.29) (xy 317.5 36.83)
		)
		(stroke
			(width 0)
			(type default)
		)
	)
	(wire
		(pts
			(xy 182.88 146.05) (xy 187.96 146.05)
		)
		(stroke
			(width 0)
			(type default)
		)
	)
	(wire
		(pts
			(xy 17.78 68.58) (xy 17.78 67.31)
		)
		(stroke
			(width 0)
			(type default)
		)
	)
	(wire
		(pts
			(xy 78.74 59.69) (xy 78.74 60.96)
		)
		(stroke
			(width 0)
			(type default)
		)
	)
	(wire
		(pts
			(xy 78.74 49.53) (xy 88.9 49.53)
		)
		(stroke
			(width 0)
			(type default)
		)
	)
	(wire
		(pts
			(xy 228.6 179.07) (xy 228.6 190.5)
		)
		(stroke
			(width 0)
			(type default)
		)
	)
	(wire
		(pts
			(xy 88.9 41.91) (xy 99.06 41.91)
		)
		(stroke
			(width 0)
			(type default)
		)
	)
	(bus
		(pts
			(xy 52.07 269.24) (xy 53.34 270.51)
		)
		(stroke
			(width 0)
			(type default)
		)
	)
	(wire
		(pts
			(xy 226.06 241.3) (xy 226.06 242.57)
		)
		(stroke
			(width 0)
			(type default)
		)
	)
	(wire
		(pts
			(xy 57.15 243.84) (xy 83.82 243.84)
		)
		(stroke
			(width 0)
			(type default)
		)
	)
	(wire
		(pts
			(xy 361.95 31.75) (xy 370.84 31.75)
		)
		(stroke
			(width 0)
			(type default)
		)
	)
	(bus
		(pts
			(xy 72.39 73.66) (xy 71.12 72.39)
		)
		(stroke
			(width 0)
			(type default)
		)
	)
	(wire
		(pts
			(xy 182.88 76.2) (xy 200.66 76.2)
		)
		(stroke
			(width 0)
			(type default)
		)
	)
	(wire
		(pts
			(xy 320.04 106.68) (xy 320.04 110.49)
		)
		(stroke
			(width 0)
			(type default)
		)
	)
	(wire
		(pts
			(xy 73.66 77.47) (xy 99.06 77.47)
		)
		(stroke
			(width 0)
			(type default)
		)
	)
	(wire
		(pts
			(xy 344.17 91.44) (xy 346.71 88.9)
		)
		(stroke
			(width 0)
			(type default)
		)
	)
	(wire
		(pts
			(xy 148.59 231.14) (xy 152.4 231.14)
		)
		(stroke
			(width 0)
			(type default)
		)
	)
	(wire
		(pts
			(xy 107.95 171.45) (xy 127 171.45)
		)
		(stroke
			(width 0)
			(type default)
		)
	)
	(wire
		(pts
			(xy 148.59 261.62) (xy 148.59 265.43)
		)
		(stroke
			(width 0)
			(type default)
		)
	)
	(wire
		(pts
			(xy 27.94 95.25) (xy 41.91 95.25)
		)
		(stroke
			(width 0)
			(type default)
		)
	)
	(wire
		(pts
			(xy 260.35 228.6) (xy 284.48 228.6)
		)
		(stroke
			(width 0)
			(type default)
		)
	)
	(wire
		(pts
			(xy 322.58 226.06) (xy 322.58 232.41)
		)
		(stroke
			(width 0)
			(type default)
		)
	)
	(wire
		(pts
			(xy 114.3 116.84) (xy 127 116.84)
		)
		(stroke
			(width 0)
			(type default)
		)
	)
	(wire
		(pts
			(xy 374.65 31.75) (xy 393.7 31.75)
		)
		(stroke
			(width 0)
			(type default)
		)
	)
	(wire
		(pts
			(xy 68.58 49.53) (xy 78.74 49.53)
		)
		(stroke
			(width 0)
			(type default)
		)
	)
	(wire
		(pts
			(xy 351.79 198.12) (xy 347.98 198.12)
		)
		(stroke
			(width 0)
			(type default)
		)
	)
	(wire
		(pts
			(xy 260.35 68.58) (xy 320.04 68.58)
		)
		(stroke
			(width 0)
			(type default)
		)
	)
	(wire
		(pts
			(xy 68.58 41.91) (xy 78.74 41.91)
		)
		(stroke
			(width 0)
			(type default)
		)
	)
	(wire
		(pts
			(xy 308.61 232.41) (xy 312.42 232.41)
		)
		(stroke
			(width 0)
			(type default)
		)
	)
	(wire
		(pts
			(xy 347.98 31.75) (xy 347.98 55.88)
		)
		(stroke
			(width 0)
			(type default)
		)
	)
	(wire
		(pts
			(xy 181.61 255.27) (xy 193.04 255.27)
		)
		(stroke
			(width 0)
			(type default)
		)
	)
	(wire
		(pts
			(xy 314.96 220.98) (xy 344.17 220.98)
		)
		(stroke
			(width 0)
			(type default)
		)
	)
	(bus
		(pts
			(xy 100.33 135.89) (xy 100.33 138.43)
		)
		(stroke
			(width 0)
			(type default)
		)
	)
	(wire
		(pts
			(xy 260.35 81.28) (xy 336.55 81.28)
		)
		(stroke
			(width 0)
			(type default)
		)
	)
	(wire
		(pts
			(xy 341.63 88.9) (xy 341.63 110.49)
		)
		(stroke
			(width 0)
			(type default)
		)
	)
	(wire
		(pts
			(xy 351.79 190.5) (xy 350.52 190.5)
		)
		(stroke
			(width 0)
			(type default)
		)
	)
	(wire
		(pts
			(xy 29.21 41.91) (xy 29.21 43.18)
		)
		(stroke
			(width 0)
			(type default)
		)
	)
	(wire
		(pts
			(xy 148.59 241.3) (xy 151.13 241.3)
		)
		(stroke
			(width 0)
			(type default)
		)
	)
	(wire
		(pts
			(xy 317.5 31.75) (xy 318.77 31.75)
		)
		(stroke
			(width 0)
			(type default)
		)
	)
	(wire
		(pts
			(xy 236.22 163.83) (xy 236.22 165.1)
		)
		(stroke
			(width 0)
			(type default)
		)
	)
	(wire
		(pts
			(xy 114.3 93.98) (xy 127 93.98)
		)
		(stroke
			(width 0)
			(type default)
		)
	)
	(wire
		(pts
			(xy 347.98 76.2) (xy 347.98 71.12)
		)
		(stroke
			(width 0)
			(type default)
		)
	)
	(wire
		(pts
			(xy 198.12 195.58) (xy 198.12 196.85)
		)
		(stroke
			(width 0)
			(type default)
		)
	)
	(wire
		(pts
			(xy 172.72 231.14) (xy 176.53 231.14)
		)
		(stroke
			(width 0)
			(type default)
		)
	)
	(wire
		(pts
			(xy 27.94 119.38) (xy 27.94 120.65)
		)
		(stroke
			(width 0)
			(type default)
		)
	)
	(wire
		(pts
			(xy 148.59 255.27) (xy 152.4 255.27)
		)
		(stroke
			(width 0)
			(type default)
		)
	)
	(wire
		(pts
			(xy 289.56 106.68) (xy 320.04 106.68)
		)
		(stroke
			(width 0)
			(type default)
		)
	)
	(wire
		(pts
			(xy 57.15 251.46) (xy 78.74 251.46)
		)
		(stroke
			(width 0)
			(type default)
		)
	)
	(wire
		(pts
			(xy 347.98 198.12) (xy 347.98 193.04)
		)
		(stroke
			(width 0)
			(type default)
		)
	)
	(wire
		(pts
			(xy 182.88 68.58) (xy 200.66 68.58)
		)
		(stroke
			(width 0)
			(type default)
		)
	)
	(wire
		(pts
			(xy 351.79 31.75) (xy 351.79 33.02)
		)
		(stroke
			(width 0)
			(type default)
		)
	)
	(wire
		(pts
			(xy 73.66 80.01) (xy 96.52 80.01)
		)
		(stroke
			(width 0)
			(type default)
		)
	)
	(wire
		(pts
			(xy 148.59 254) (xy 148.59 255.27)
		)
		(stroke
			(width 0)
			(type default)
		)
	)
	(wire
		(pts
			(xy 193.04 161.29) (xy 201.93 161.29)
		)
		(stroke
			(width 0)
			(type default)
		)
	)
	(wire
		(pts
			(xy 27.94 198.12) (xy 27.94 196.85)
		)
		(stroke
			(width 0)
			(type default)
		)
	)
	(wire
		(pts
			(xy 48.26 59.69) (xy 48.26 60.96)
		)
		(stroke
			(width 0)
			(type default)
		)
	)
	(wire
		(pts
			(xy 198.12 186.69) (xy 198.12 190.5)
		)
		(stroke
			(width 0)
			(type default)
		)
	)
	(wire
		(pts
			(xy 109.22 67.31) (xy 109.22 66.04)
		)
		(stroke
			(width 0)
			(type default)
		)
	)
	(wire
		(pts
			(xy 308.61 110.49) (xy 308.61 113.03)
		)
		(stroke
			(width 0)
			(type default)
		)
	)
	(wire
		(pts
			(xy 346.71 81.28) (xy 351.79 81.28)
		)
		(stroke
			(width 0)
			(type default)
		)
	)
	(wire
		(pts
			(xy 182.88 86.36) (xy 200.66 86.36)
		)
		(stroke
			(width 0)
			(type default)
		)
	)
	(wire
		(pts
			(xy 118.11 64.77) (xy 127 64.77)
		)
		(stroke
			(width 0)
			(type default)
		)
	)
	(wire
		(pts
			(xy 48.26 41.91) (xy 58.42 41.91)
		)
		(stroke
			(width 0)
			(type default)
		)
	)
	(wire
		(pts
			(xy 260.35 99.06) (xy 314.96 99.06)
		)
		(stroke
			(width 0)
			(type default)
		)
	)
	(wire
		(pts
			(xy 392.43 153.67) (xy 392.43 154.94)
		)
		(stroke
			(width 0)
			(type default)
		)
	)
	(wire
		(pts
			(xy 182.88 71.12) (xy 200.66 71.12)
		)
		(stroke
			(width 0)
			(type default)
		)
	)
	(wire
		(pts
			(xy 114.3 114.3) (xy 127 114.3)
		)
		(stroke
			(width 0)
			(type default)
		)
	)
	(wire
		(pts
			(xy 114.3 101.6) (xy 127 101.6)
		)
		(stroke
			(width 0)
			(type default)
		)
	)
	(wire
		(pts
			(xy 182.88 119.38) (xy 200.66 119.38)
		)
		(stroke
			(width 0)
			(type default)
		)
	)
	(wire
		(pts
			(xy 88.9 59.69) (xy 88.9 60.96)
		)
		(stroke
			(width 0)
			(type default)
		)
	)
	(wire
		(pts
			(xy 81.28 246.38) (xy 81.28 276.86)
		)
		(stroke
			(width 0)
			(type default)
		)
	)
	(wire
		(pts
			(xy 360.68 153.67) (xy 360.68 154.94)
		)
		(stroke
			(width 0)
			(type default)
		)
	)
	(wire
		(pts
			(xy 347.98 193.04) (xy 351.79 193.04)
		)
		(stroke
			(width 0)
			(type default)
		)
	)
	(wire
		(pts
			(xy 231.14 231.14) (xy 234.95 231.14)
		)
		(stroke
			(width 0)
			(type default)
		)
	)
	(wire
		(pts
			(xy 57.15 248.92) (xy 76.2 248.92)
		)
		(stroke
			(width 0)
			(type default)
		)
	)
	(wire
		(pts
			(xy 167.64 236.22) (xy 193.04 236.22)
		)
		(stroke
			(width 0)
			(type default)
		)
	)
	(wire
		(pts
			(xy 260.35 96.52) (xy 317.5 96.52)
		)
		(stroke
			(width 0)
			(type default)
		)
	)
	(wire
		(pts
			(xy 57.15 256.54) (xy 72.39 256.54)
		)
		(stroke
			(width 0)
			(type default)
		)
	)
	(wire
		(pts
			(xy 337.82 41.91) (xy 335.28 41.91)
		)
		(stroke
			(width 0)
			(type default)
		)
	)
	(wire
		(pts
			(xy 182.88 184.15) (xy 205.74 184.15)
		)
		(stroke
			(width 0)
			(type default)
		)
	)
	(wire
		(pts
			(xy 369.57 153.67) (xy 373.38 153.67)
		)
		(stroke
			(width 0)
			(type default)
		)
	)
	(wire
		(pts
			(xy 78.74 67.31) (xy 78.74 66.04)
		)
		(stroke
			(width 0)
			(type default)
		)
	)
	(wire
		(pts
			(xy 58.42 59.69) (xy 58.42 60.96)
		)
		(stroke
			(width 0)
			(type default)
		)
	)
	(wire
		(pts
			(xy 336.55 163.83) (xy 334.01 163.83)
		)
		(stroke
			(width 0)
			(type default)
		)
	)
	(wire
		(pts
			(xy 182.88 93.98) (xy 200.66 93.98)
		)
		(stroke
			(width 0)
			(type default)
		)
	)
	(wire
		(pts
			(xy 334.01 36.83) (xy 335.28 36.83)
		)
		(stroke
			(width 0)
			(type default)
		)
	)
	(wire
		(pts
			(xy 393.7 31.75) (xy 393.7 33.02)
		)
		(stroke
			(width 0)
			(type default)
		)
	)
	(wire
		(pts
			(xy 350.52 121.92) (xy 350.52 119.38)
		)
		(stroke
			(width 0)
			(type default)
		)
	)
	(wire
		(pts
			(xy 80.01 148.59) (xy 80.01 151.13)
		)
		(stroke
			(width 0)
			(type default)
		)
	)
	(bus
		(pts
			(xy 100.33 135.89) (xy 99.06 134.62)
		)
		(stroke
			(width 0)
			(type default)
		)
	)
	(wire
		(pts
			(xy 334.01 83.82) (xy 334.01 110.49)
		)
		(stroke
			(width 0)
			(type default)
		)
	)
	(wire
		(pts
			(xy 124.46 189.23) (xy 124.46 186.69)
		)
		(stroke
			(width 0)
			(type default)
		)
	)
	(wire
		(pts
			(xy 207.01 254) (xy 207.01 255.27)
		)
		(stroke
			(width 0)
			(type default)
		)
	)
	(wire
		(pts
			(xy 236.22 165.1) (xy 228.6 165.1)
		)
		(stroke
			(width 0)
			(type default)
		)
	)
	(wire
		(pts
			(xy 78.74 251.46) (xy 78.74 274.32)
		)
		(stroke
			(width 0)
			(type default)
		)
	)
	(wire
		(pts
			(xy 124.46 186.69) (xy 127 186.69)
		)
		(stroke
			(width 0)
			(type default)
		)
	)
	(wire
		(pts
			(xy 78.74 41.91) (xy 78.74 43.18)
		)
		(stroke
			(width 0)
			(type default)
		)
	)
	(wire
		(pts
			(xy 260.35 83.82) (xy 334.01 83.82)
		)
		(stroke
			(width 0)
			(type default)
		)
	)
	(wire
		(pts
			(xy 27.94 125.73) (xy 27.94 128.27)
		)
		(stroke
			(width 0)
			(type default)
		)
	)
	(wire
		(pts
			(xy 344.17 81.28) (xy 346.71 83.82)
		)
		(stroke
			(width 0)
			(type default)
		)
	)
	(wire
		(pts
			(xy 236.22 165.1) (xy 236.22 166.37)
		)
		(stroke
			(width 0)
			(type default)
		)
	)
	(wire
		(pts
			(xy 151.13 236.22) (xy 151.13 241.3)
		)
		(stroke
			(width 0)
			(type default)
		)
	)
	(wire
		(pts
			(xy 361.95 31.75) (xy 361.95 33.02)
		)
		(stroke
			(width 0)
			(type default)
		)
	)
	(wire
		(pts
			(xy 193.04 151.13) (xy 201.93 151.13)
		)
		(stroke
			(width 0)
			(type default)
		)
	)
	(wire
		(pts
			(xy 215.9 101.6) (xy 228.6 101.6)
		)
		(stroke
			(width 0)
			(type default)
		)
	)
	(wire
		(pts
			(xy 148.59 255.27) (xy 148.59 256.54)
		)
		(stroke
			(width 0)
			(type default)
		)
	)
	(wire
		(pts
			(xy 92.71 241.3) (xy 80.01 241.3)
		)
		(stroke
			(width 0)
			(type default)
		)
	)
	(wire
		(pts
			(xy 260.35 185.42) (xy 318.77 185.42)
		)
		(stroke
			(width 0)
			(type default)
		)
	)
	(wire
		(pts
			(xy 120.65 184.15) (xy 127 184.15)
		)
		(stroke
			(width 0)
			(type default)
		)
	)
	(wire
		(pts
			(xy 27.94 87.63) (xy 27.94 88.9)
		)
		(stroke
			(width 0)
			(type default)
		)
	)
	(wire
		(pts
			(xy 350.52 121.92) (xy 351.79 121.92)
		)
		(stroke
			(width 0)
			(type default)
		)
	)
	(wire
		(pts
			(xy 223.52 255.27) (xy 226.06 255.27)
		)
		(stroke
			(width 0)
			(type default)
		)
	)
	(wire
		(pts
			(xy 100.33 170.18) (xy 100.33 173.99)
		)
		(stroke
			(width 0)
			(type default)
		)
	)
	(wire
		(pts
			(xy 344.17 220.98) (xy 346.71 218.44)
		)
		(stroke
			(width 0)
			(type default)
		)
	)
	(wire
		(pts
			(xy 327.66 232.41) (xy 327.66 236.22)
		)
		(stroke
			(width 0)
			(type default)
		)
	)
	(wire
		(pts
			(xy 54.61 274.32) (xy 78.74 274.32)
		)
		(stroke
			(width 0)
			(type default)
		)
	)
	(wire
		(pts
			(xy 88.9 49.53) (xy 88.9 48.26)
		)
		(stroke
			(width 0)
			(type default)
		)
	)
	(wire
		(pts
			(xy 344.17 83.82) (xy 346.71 81.28)
		)
		(stroke
			(width 0)
			(type default)
		)
	)
	(wire
		(pts
			(xy 27.94 185.42) (xy 27.94 191.77)
		)
		(stroke
			(width 0)
			(type default)
		)
	)
	(wire
		(pts
			(xy 31.75 254) (xy 52.07 254)
		)
		(stroke
			(width 0)
			(type default)
		)
	)
	(bus
		(pts
			(xy 72.39 83.82) (xy 71.12 82.55)
		)
		(stroke
			(width 0)
			(type default)
		)
	)
	(wire
		(pts
			(xy 99.06 41.91) (xy 109.22 41.91)
		)
		(stroke
			(width 0)
			(type default)
		)
	)
	(wire
		(pts
			(xy 58.42 67.31) (xy 58.42 66.04)
		)
		(stroke
			(width 0)
			(type default)
		)
	)
	(wire
		(pts
			(xy 100.33 173.99) (xy 127 173.99)
		)
		(stroke
			(width 0)
			(type default)
		)
	)
	(wire
		(pts
			(xy 360.68 160.02) (xy 360.68 161.29)
		)
		(stroke
			(width 0)
			(type default)
		)
	)
	(wire
		(pts
			(xy 81.28 246.38) (xy 92.71 246.38)
		)
		(stroke
			(width 0)
			(type default)
		)
	)
	(wire
		(pts
			(xy 152.4 265.43) (xy 151.13 265.43)
		)
		(stroke
			(width 0)
			(type default)
		)
	)
	(wire
		(pts
			(xy 317.5 36.83) (xy 318.77 36.83)
		)
		(stroke
			(width 0)
			(type default)
		)
	)
	(wire
		(pts
			(xy 58.42 59.69) (xy 68.58 59.69)
		)
		(stroke
			(width 0)
			(type default)
		)
	)
	(wire
		(pts
			(xy 341.63 88.9) (xy 344.17 88.9)
		)
		(stroke
			(width 0)
			(type default)
		)
	)
	(wire
		(pts
			(xy 369.57 151.13) (xy 369.57 153.67)
		)
		(stroke
			(width 0)
			(type default)
		)
	)
	(wire
		(pts
			(xy 100.33 165.1) (xy 100.33 163.83)
		)
		(stroke
			(width 0)
			(type default)
		)
	)
	(wire
		(pts
			(xy 393.7 38.1) (xy 393.7 39.37)
		)
		(stroke
			(width 0)
			(type default)
		)
	)
	(wire
		(pts
			(xy 100.33 163.83) (xy 107.95 163.83)
		)
		(stroke
			(width 0)
			(type default)
		)
	)
	(wire
		(pts
			(xy 346.71 153.67) (xy 350.52 153.67)
		)
		(stroke
			(width 0)
			(type default)
		)
	)
	(wire
		(pts
			(xy 92.71 238.76) (xy 80.01 238.76)
		)
		(stroke
			(width 0)
			(type default)
		)
	)
	(wire
		(pts
			(xy 314.96 99.06) (xy 314.96 110.49)
		)
		(stroke
			(width 0)
			(type default)
		)
	)
	(wire
		(pts
			(xy 58.42 67.31) (xy 68.58 67.31)
		)
		(stroke
			(width 0)
			(type default)
		)
	)
	(wire
		(pts
			(xy 209.55 260.35) (xy 210.82 260.35)
		)
		(stroke
			(width 0)
			(type default)
		)
	)
	(wire
		(pts
			(xy 320.04 228.6) (xy 351.79 228.6)
		)
		(stroke
			(width 0)
			(type default)
		)
	)
	(wire
		(pts
			(xy 114.3 96.52) (xy 127 96.52)
		)
		(stroke
			(width 0)
			(type default)
		)
	)
	(wire
		(pts
			(xy 199.39 146.05) (xy 199.39 163.83)
		)
		(stroke
			(width 0)
			(type default)
		)
	)
	(wire
		(pts
			(xy 207.01 241.3) (xy 209.55 241.3)
		)
		(stroke
			(width 0)
			(type default)
		)
	)
	(wire
		(pts
			(xy 114.3 129.54) (xy 127 129.54)
		)
		(stroke
			(width 0)
			(type default)
		)
	)
	(wire
		(pts
			(xy 208.28 101.6) (xy 210.82 101.6)
		)
		(stroke
			(width 0)
			(type default)
		)
	)
	(wire
		(pts
			(xy 74.93 233.68) (xy 74.93 234.95)
		)
		(stroke
			(width 0)
			(type default)
		)
	)
	(wire
		(pts
			(xy 109.22 49.53) (xy 109.22 48.26)
		)
		(stroke
			(width 0)
			(type default)
		)
	)
	(wire
		(pts
			(xy 308.61 110.49) (xy 312.42 110.49)
		)
		(stroke
			(width 0)
			(type default)
		)
	)
	(wire
		(pts
			(xy 121.92 148.59) (xy 121.92 154.94)
		)
		(stroke
			(width 0)
			(type default)
		)
	)
	(wire
		(pts
			(xy 165.1 260.35) (xy 167.64 260.35)
		)
		(stroke
			(width 0)
			(type default)
		)
	)
	(wire
		(pts
			(xy 350.52 121.92) (xy 350.52 123.19)
		)
		(stroke
			(width 0)
			(type default)
		)
	)
	(wire
		(pts
			(xy 205.74 195.58) (xy 205.74 196.85)
		)
		(stroke
			(width 0)
			(type default)
		)
	)
	(wire
		(pts
			(xy 35.56 187.96) (xy 35.56 191.77)
		)
		(stroke
			(width 0)
			(type default)
		)
	)
	(wire
		(pts
			(xy 260.35 218.44) (xy 317.5 218.44)
		)
		(stroke
			(width 0)
			(type default)
		)
	)
	(wire
		(pts
			(xy 339.09 91.44) (xy 344.17 91.44)
		)
		(stroke
			(width 0)
			(type default)
		)
	)
	(wire
		(pts
			(xy 207.01 231.14) (xy 207.01 232.41)
		)
		(stroke
			(width 0)
			(type default)
		)
	)
	(wire
		(pts
			(xy 346.71 99.06) (xy 351.79 99.06)
		)
		(stroke
			(width 0)
			(type default)
		)
	)
	(wire
		(pts
			(xy 121.92 139.7) (xy 127 139.7)
		)
		(stroke
			(width 0)
			(type default)
		)
	)
	(wire
		(pts
			(xy 347.98 71.12) (xy 351.79 71.12)
		)
		(stroke
			(width 0)
			(type default)
		)
	)
	(wire
		(pts
			(xy 182.88 109.22) (xy 200.66 109.22)
		)
		(stroke
			(width 0)
			(type default)
		)
	)
	(wire
		(pts
			(xy 209.55 236.22) (xy 210.82 236.22)
		)
		(stroke
			(width 0)
			(type default)
		)
	)
	(wire
		(pts
			(xy 336.55 203.2) (xy 336.55 232.41)
		)
		(stroke
			(width 0)
			(type default)
		)
	)
	(wire
		(pts
			(xy 335.28 36.83) (xy 335.28 41.91)
		)
		(stroke
			(width 0)
			(type default)
		)
	)
	(wire
		(pts
			(xy 68.58 49.53) (xy 68.58 48.26)
		)
		(stroke
			(width 0)
			(type default)
		)
	)
	(wire
		(pts
			(xy 351.79 76.2) (xy 347.98 76.2)
		)
		(stroke
			(width 0)
			(type default)
		)
	)
	(wire
		(pts
			(xy 182.88 124.46) (xy 200.66 124.46)
		)
		(stroke
			(width 0)
			(type default)
		)
	)
	(wire
		(pts
			(xy 38.1 49.53) (xy 38.1 48.26)
		)
		(stroke
			(width 0)
			(type default)
		)
	)
	(wire
		(pts
			(xy 58.42 41.91) (xy 68.58 41.91)
		)
		(stroke
			(width 0)
			(type default)
		)
	)
	(wire
		(pts
			(xy 322.58 104.14) (xy 351.79 104.14)
		)
		(stroke
			(width 0)
			(type default)
		)
	)
	(wire
		(pts
			(xy 31.75 243.84) (xy 52.07 243.84)
		)
		(stroke
			(width 0)
			(type default)
		)
	)
	(wire
		(pts
			(xy 17.78 41.91) (xy 29.21 41.91)
		)
		(stroke
			(width 0)
			(type default)
		)
	)
	(wire
		(pts
			(xy 336.55 81.28) (xy 336.55 110.49)
		)
		(stroke
			(width 0)
			(type default)
		)
	)
	(wire
		(pts
			(xy 68.58 67.31) (xy 68.58 66.04)
		)
		(stroke
			(width 0)
			(type default)
		)
	)
	(wire
		(pts
			(xy 68.58 59.69) (xy 78.74 59.69)
		)
		(stroke
			(width 0)
			(type default)
		)
	)
	(wire
		(pts
			(xy 207.01 229.87) (xy 207.01 231.14)
		)
		(stroke
			(width 0)
			(type default)
		)
	)
	(wire
		(pts
			(xy 360.68 153.67) (xy 369.57 153.67)
		)
		(stroke
			(width 0)
			(type default)
		)
	)
	(bus
		(pts
			(xy 72.39 83.82) (xy 72.39 86.36)
		)
		(stroke
			(width 0)
			(type default)
		)
	)
	(wire
		(pts
			(xy 118.11 59.69) (xy 118.11 64.77)
		)
		(stroke
			(width 0)
			(type default)
		)
	)
	(wire
		(pts
			(xy 182.88 158.75) (xy 187.96 158.75)
		)
		(stroke
			(width 0)
			(type default)
		)
	)
	(wire
		(pts
			(xy 27.94 176.53) (xy 27.94 179.07)
		)
		(stroke
			(width 0)
			(type default)
		)
	)
	(wire
		(pts
			(xy 152.4 241.3) (xy 151.13 241.3)
		)
		(stroke
			(width 0)
			(type default)
		)
	)
	(wire
		(pts
			(xy 317.5 31.75) (xy 317.5 21.59)
		)
		(stroke
			(width 0)
			(type default)
		)
	)
	(wire
		(pts
			(xy 260.35 210.82) (xy 280.67 210.82)
		)
		(stroke
			(width 0)
			(type default)
		)
	)
	(wire
		(pts
			(xy 88.9 49.53) (xy 99.06 49.53)
		)
		(stroke
			(width 0)
			(type default)
		)
	)
	(wire
		(pts
			(xy 317.5 53.34) (xy 317.5 63.5)
		)
		(stroke
			(width 0)
			(type default)
		)
	)
	(wire
		(pts
			(xy 101.6 137.16) (xy 116.84 137.16)
		)
		(stroke
			(width 0)
			(type default)
		)
	)
	(wire
		(pts
			(xy 317.5 96.52) (xy 317.5 110.49)
		)
		(stroke
			(width 0)
			(type default)
		)
	)
	(wire
		(pts
			(xy 165.1 265.43) (xy 167.64 265.43)
		)
		(stroke
			(width 0)
			(type default)
		)
	)
	(wire
		(pts
			(xy 92.71 176.53) (xy 92.71 170.18)
		)
		(stroke
			(width 0)
			(type default)
		)
	)
	(wire
		(pts
			(xy 124.46 179.07) (xy 124.46 186.69)
		)
		(stroke
			(width 0)
			(type default)
		)
	)
	(wire
		(pts
			(xy 68.58 41.91) (xy 68.58 43.18)
		)
		(stroke
			(width 0)
			(type default)
		)
	)
	(wire
		(pts
			(xy 223.52 260.35) (xy 226.06 260.35)
		)
		(stroke
			(width 0)
			(type default)
		)
	)
	(wire
		(pts
			(xy 17.78 41.91) (xy 17.78 43.18)
		)
		(stroke
			(width 0)
			(type default)
		)
	)
	(wire
		(pts
			(xy 289.56 228.6) (xy 320.04 228.6)
		)
		(stroke
			(width 0)
			(type default)
		)
	)
	(wire
		(pts
			(xy 322.58 226.06) (xy 351.79 226.06)
		)
		(stroke
			(width 0)
			(type default)
		)
	)
	(wire
		(pts
			(xy 220.98 190.5) (xy 220.98 173.99)
		)
		(stroke
			(width 0)
			(type default)
		)
	)
	(wire
		(pts
			(xy 114.3 121.92) (xy 127 121.92)
		)
		(stroke
			(width 0)
			(type default)
		)
	)
	(wire
		(pts
			(xy 334.01 83.82) (xy 344.17 83.82)
		)
		(stroke
			(width 0)
			(type default)
		)
	)
	(wire
		(pts
			(xy 350.52 119.38) (xy 351.79 119.38)
		)
		(stroke
			(width 0)
			(type default)
		)
	)
	(wire
		(pts
			(xy 201.93 161.29) (xy 201.93 158.75)
		)
		(stroke
			(width 0)
			(type default)
		)
	)
	(wire
		(pts
			(xy 341.63 210.82) (xy 341.63 232.41)
		)
		(stroke
			(width 0)
			(type default)
		)
	)
	(wire
		(pts
			(xy 181.61 231.14) (xy 193.04 231.14)
		)
		(stroke
			(width 0)
			(type default)
		)
	)
	(wire
		(pts
			(xy 226.06 236.22) (xy 251.46 236.22)
		)
		(stroke
			(width 0)
			(type default)
		)
	)
	(wire
		(pts
			(xy 182.88 63.5) (xy 208.28 63.5)
		)
		(stroke
			(width 0)
			(type default)
		)
	)
	(wire
		(pts
			(xy 327.66 232.41) (xy 331.47 232.41)
		)
		(stroke
			(width 0)
			(type default)
		)
	)
	(wire
		(pts
			(xy 344.17 96.52) (xy 346.71 99.06)
		)
		(stroke
			(width 0)
			(type default)
		)
	)
	(wire
		(pts
			(xy 323.85 176.53) (xy 323.85 190.5)
		)
		(stroke
			(width 0)
			(type default)
		)
	)
	(wire
		(pts
			(xy 101.6 80.01) (xy 127 80.01)
		)
		(stroke
			(width 0)
			(type default)
		)
	)
	(wire
		(pts
			(xy 182.88 78.74) (xy 200.66 78.74)
		)
		(stroke
			(width 0)
			(type default)
		)
	)
	(wire
		(pts
			(xy 182.88 173.99) (xy 220.98 173.99)
		)
		(stroke
			(width 0)
			(type default)
		)
	)
	(wire
		(pts
			(xy 392.43 160.02) (xy 392.43 161.29)
		)
		(stroke
			(width 0)
			(type default)
		)
	)
	(wire
		(pts
			(xy 54.61 276.86) (xy 81.28 276.86)
		)
		(stroke
			(width 0)
			(type default)
		)
	)
	(wire
		(pts
			(xy 316.23 158.75) (xy 317.5 158.75)
		)
		(stroke
			(width 0)
			(type default)
		)
	)
	(wire
		(pts
			(xy 29.21 41.91) (xy 38.1 41.91)
		)
		(stroke
			(width 0)
			(type default)
		)
	)
	(wire
		(pts
			(xy 223.52 236.22) (xy 226.06 236.22)
		)
		(stroke
			(width 0)
			(type default)
		)
	)
	(wire
		(pts
			(xy 114.3 99.06) (xy 127 99.06)
		)
		(stroke
			(width 0)
			(type default)
		)
	)
	(wire
		(pts
			(xy 207.01 255.27) (xy 207.01 256.54)
		)
		(stroke
			(width 0)
			(type default)
		)
	)
	(wire
		(pts
			(xy 80.01 148.59) (xy 82.55 148.59)
		)
		(stroke
			(width 0)
			(type default)
		)
	)
	(wire
		(pts
			(xy 334.01 205.74) (xy 344.17 205.74)
		)
		(stroke
			(width 0)
			(type default)
		)
	)
	(wire
		(pts
			(xy 123.19 41.91) (xy 123.19 62.23)
		)
		(stroke
			(width 0)
			(type default)
		)
	)
	(wire
		(pts
			(xy 260.35 226.06) (xy 280.67 226.06)
		)
		(stroke
			(width 0)
			(type default)
		)
	)
	(wire
		(pts
			(xy 27.94 102.87) (xy 27.94 101.6)
		)
		(stroke
			(width 0)
			(type default)
		)
	)
	(wire
		(pts
			(xy 302.26 158.75) (xy 316.23 158.75)
		)
		(stroke
			(width 0)
			(type default)
		)
	)
	(wire
		(pts
			(xy 182.88 132.08) (xy 200.66 132.08)
		)
		(stroke
			(width 0)
			(type default)
		)
	)
	(wire
		(pts
			(xy 57.15 254) (xy 72.39 254)
		)
		(stroke
			(width 0)
			(type default)
		)
	)
	(wire
		(pts
			(xy 344.17 88.9) (xy 346.71 91.44)
		)
		(stroke
			(width 0)
			(type default)
		)
	)
	(wire
		(pts
			(xy 260.35 106.68) (xy 284.48 106.68)
		)
		(stroke
			(width 0)
			(type default)
		)
	)
	(wire
		(pts
			(xy 350.52 68.58) (xy 350.52 73.66)
		)
		(stroke
			(width 0)
			(type default)
		)
	)
	(wire
		(pts
			(xy 182.88 104.14) (xy 200.66 104.14)
		)
		(stroke
			(width 0)
			(type default)
		)
	)
	(wire
		(pts
			(xy 308.61 232.41) (xy 308.61 234.95)
		)
		(stroke
			(width 0)
			(type default)
		)
	)
	(wire
		(pts
			(xy 48.26 41.91) (xy 38.1 41.91)
		)
		(stroke
			(width 0)
			(type default)
		)
	)
	(wire
		(pts
			(xy 334.01 31.75) (xy 347.98 31.75)
		)
		(stroke
			(width 0)
			(type default)
		)
	)
	(wire
		(pts
			(xy 182.88 73.66) (xy 200.66 73.66)
		)
		(stroke
			(width 0)
			(type default)
		)
	)
	(wire
		(pts
			(xy 344.17 205.74) (xy 346.71 203.2)
		)
		(stroke
			(width 0)
			(type default)
		)
	)
	(wire
		(pts
			(xy 78.74 251.46) (xy 92.71 251.46)
		)
		(stroke
			(width 0)
			(type default)
		)
	)
	(wire
		(pts
			(xy 78.74 67.31) (xy 88.9 67.31)
		)
		(stroke
			(width 0)
			(type default)
		)
	)
	(wire
		(pts
			(xy 208.28 63.5) (xy 208.28 64.77)
		)
		(stroke
			(width 0)
			(type default)
		)
	)
	(wire
		(pts
			(xy 17.78 49.53) (xy 29.21 49.53)
		)
		(stroke
			(width 0)
			(type default)
		)
	)
	(wire
		(pts
			(xy 167.64 260.35) (xy 193.04 260.35)
		)
		(stroke
			(width 0)
			(type default)
		)
	)
	(wire
		(pts
			(xy 87.63 224.79) (xy 87.63 226.06)
		)
		(stroke
			(width 0)
			(type default)
		)
	)
	(wire
		(pts
			(xy 350.52 153.67) (xy 360.68 153.67)
		)
		(stroke
			(width 0)
			(type default)
		)
	)
	(wire
		(pts
			(xy 27.94 135.89) (xy 27.94 137.16)
		)
		(stroke
			(width 0)
			(type default)
		)
	)
	(wire
		(pts
			(xy 74.93 226.06) (xy 74.93 228.6)
		)
		(stroke
			(width 0)
			(type default)
		)
	)
	(wire
		(pts
			(xy 323.85 190.5) (xy 350.52 190.5)
		)
		(stroke
			(width 0)
			(type default)
		)
	)
	(wire
		(pts
			(xy 83.82 243.84) (xy 83.82 279.4)
		)
		(stroke
			(width 0)
			(type default)
		)
	)
	(wire
		(pts
			(xy 91.44 257.81) (xy 91.44 256.54)
		)
		(stroke
			(width 0)
			(type default)
		)
	)
	(wire
		(pts
			(xy 316.23 156.21) (xy 316.23 158.75)
		)
		(stroke
			(width 0)
			(type default)
		)
	)
	(wire
		(pts
			(xy 78.74 59.69) (xy 88.9 59.69)
		)
		(stroke
			(width 0)
			(type default)
		)
	)
	(wire
		(pts
			(xy 207.01 237.49) (xy 207.01 241.3)
		)
		(stroke
			(width 0)
			(type default)
		)
	)
	(wire
		(pts
			(xy 121.92 137.16) (xy 127 137.16)
		)
		(stroke
			(width 0)
			(type default)
		)
	)
	(wire
		(pts
			(xy 208.28 101.6) (xy 208.28 102.87)
		)
		(stroke
			(width 0)
			(type default)
		)
	)
	(bus
		(pts
			(xy 68.58 72.39) (xy 71.12 72.39)
		)
		(stroke
			(width 0)
			(type default)
		)
	)
	(wire
		(pts
			(xy 165.1 255.27) (xy 167.64 255.27)
		)
		(stroke
			(width 0)
			(type default)
		)
	)
	(wire
		(pts
			(xy 351.79 38.1) (xy 351.79 39.37)
		)
		(stroke
			(width 0)
			(type default)
		)
	)
	(wire
		(pts
			(xy 374.65 38.1) (xy 374.65 39.37)
		)
		(stroke
			(width 0)
			(type default)
		)
	)
	(wire
		(pts
			(xy 92.71 165.1) (xy 92.71 163.83)
		)
		(stroke
			(width 0)
			(type default)
		)
	)
	(wire
		(pts
			(xy 48.26 41.91) (xy 48.26 43.18)
		)
		(stroke
			(width 0)
			(type default)
		)
	)
	(wire
		(pts
			(xy 373.38 153.67) (xy 392.43 153.67)
		)
		(stroke
			(width 0)
			(type default)
		)
	)
	(wire
		(pts
			(xy 285.75 88.9) (xy 341.63 88.9)
		)
		(stroke
			(width 0)
			(type default)
		)
	)
	(wire
		(pts
			(xy 109.22 59.69) (xy 118.11 59.69)
		)
		(stroke
			(width 0)
			(type default)
		)
	)
	(polyline
		(pts
			(xy 137.16 210.312) (xy 137.16 284.48)
		)
		(stroke
			(width 0)
			(type default)
		)
	)
	(wire
		(pts
			(xy 307.34 143.51) (xy 307.34 144.78)
		)
		(stroke
			(width 0)
			(type default)
		)
	)
	(wire
		(pts
			(xy 346.71 91.44) (xy 351.79 91.44)
		)
		(stroke
			(width 0)
			(type default)
		)
	)
	(wire
		(pts
			(xy 17.78 67.31) (xy 38.1 67.31)
		)
		(stroke
			(width 0)
			(type default)
		)
	)
	(wire
		(pts
			(xy 167.64 241.3) (xy 167.64 242.57)
		)
		(stroke
			(width 0)
			(type default)
		)
	)
	(wire
		(pts
			(xy 38.1 59.69) (xy 38.1 60.96)
		)
		(stroke
			(width 0)
			(type default)
		)
	)
	(wire
		(pts
			(xy 114.3 165.1) (xy 127 165.1)
		)
		(stroke
			(width 0)
			(type default)
		)
	)
	(wire
		(pts
			(xy 182.88 106.68) (xy 200.66 106.68)
		)
		(stroke
			(width 0)
			(type default)
		)
	)
	(wire
		(pts
			(xy 92.71 233.68) (xy 87.63 233.68)
		)
		(stroke
			(width 0)
			(type default)
		)
	)
	(wire
		(pts
			(xy 73.66 87.63) (xy 127 87.63)
		)
		(stroke
			(width 0)
			(type default)
		)
	)
	(wire
		(pts
			(xy 220.98 196.85) (xy 220.98 195.58)
		)
		(stroke
			(width 0)
			(type default)
		)
	)
	(bus
		(pts
			(xy 53.34 273.05) (xy 53.34 275.59)
		)
		(stroke
			(width 0)
			(type default)
		)
	)
	(wire
		(pts
			(xy 346.71 220.98) (xy 351.79 220.98)
		)
		(stroke
			(width 0)
			(type default)
		)
	)
	(wire
		(pts
			(xy 260.35 71.12) (xy 322.58 71.12)
		)
		(stroke
			(width 0)
			(type default)
		)
	)
	(wire
		(pts
			(xy 57.15 246.38) (xy 81.28 246.38)
		)
		(stroke
			(width 0)
			(type default)
		)
	)
	(polyline
		(pts
			(xy 11.938 72.898) (xy 11.938 73.66)
		)
		(stroke
			(width 0)
			(type default)
		)
	)
	(wire
		(pts
			(xy 228.6 166.37) (xy 228.6 165.1)
		)
		(stroke
			(width 0)
			(type default)
		)
	)
	(wire
		(pts
			(xy 207.01 265.43) (xy 209.55 265.43)
		)
		(stroke
			(width 0)
			(type default)
		)
	)
	(bus
		(pts
			(xy 53.34 270.51) (xy 53.34 273.05)
		)
		(stroke
			(width 0)
			(type default)
		)
	)
	(wire
		(pts
			(xy 320.04 53.34) (xy 320.04 68.58)
		)
		(stroke
			(width 0)
			(type default)
		)
	)
	(wire
		(pts
			(xy 78.74 49.53) (xy 78.74 48.26)
		)
		(stroke
			(width 0)
			(type default)
		)
	)
	(wire
		(pts
			(xy 260.35 88.9) (xy 280.67 88.9)
		)
		(stroke
			(width 0)
			(type default)
		)
	)
	(wire
		(pts
			(xy 88.9 67.31) (xy 99.06 67.31)
		)
		(stroke
			(width 0)
			(type default)
		)
	)
	(wire
		(pts
			(xy 109.22 41.91) (xy 109.22 43.18)
		)
		(stroke
			(width 0)
			(type default)
		)
	)
	(wire
		(pts
			(xy 82.55 151.13) (xy 80.01 151.13)
		)
		(stroke
			(width 0)
			(type default)
		)
	)
	(wire
		(pts
			(xy 148.59 229.87) (xy 148.59 231.14)
		)
		(stroke
			(width 0)
			(type default)
		)
	)
	(wire
		(pts
			(xy 236.22 176.53) (xy 236.22 190.5)
		)
		(stroke
			(width 0)
			(type default)
		)
	)
	(wire
		(pts
			(xy 114.3 162.56) (xy 127 162.56)
		)
		(stroke
			(width 0)
			(type default)
		)
	)
	(wire
		(pts
			(xy 392.43 166.37) (xy 392.43 167.64)
		)
		(stroke
			(width 0)
			(type default)
		)
	)
	(wire
		(pts
			(xy 346.71 96.52) (xy 351.79 96.52)
		)
		(stroke
			(width 0)
			(type default)
		)
	)
	(wire
		(pts
			(xy 87.63 226.06) (xy 74.93 226.06)
		)
		(stroke
			(width 0)
			(type default)
		)
	)
	(wire
		(pts
			(xy 17.78 59.69) (xy 17.78 60.96)
		)
		(stroke
			(width 0)
			(type default)
		)
	)
	(wire
		(pts
			(xy 68.58 59.69) (xy 68.58 60.96)
		)
		(stroke
			(width 0)
			(type default)
		)
	)
	(wire
		(pts
			(xy 27.94 128.27) (xy 49.53 128.27)
		)
		(stroke
			(width 0)
			(type default)
		)
	)
	(wire
		(pts
			(xy 289.56 213.36) (xy 339.09 213.36)
		)
		(stroke
			(width 0)
			(type default)
		)
	)
	(wire
		(pts
			(xy 336.55 203.2) (xy 344.17 203.2)
		)
		(stroke
			(width 0)
			(type default)
		)
	)
	(wire
		(pts
			(xy 38.1 49.53) (xy 48.26 49.53)
		)
		(stroke
			(width 0)
			(type default)
		)
	)
	(wire
		(pts
			(xy 303.53 36.83) (xy 317.5 36.83)
		)
		(stroke
			(width 0)
			(type default)
		)
	)
	(wire
		(pts
			(xy 347.98 31.75) (xy 351.79 31.75)
		)
		(stroke
			(width 0)
			(type default)
		)
	)
	(wire
		(pts
			(xy 361.95 38.1) (xy 361.95 39.37)
		)
		(stroke
			(width 0)
			(type default)
		)
	)
	(wire
		(pts
			(xy 308.61 20.32) (xy 308.61 21.59)
		)
		(stroke
			(width 0)
			(type default)
		)
	)
	(wire
		(pts
			(xy 316.23 153.67) (xy 316.23 143.51)
		)
		(stroke
			(width 0)
			(type default)
		)
	)
	(wire
		(pts
			(xy 393.7 44.45) (xy 393.7 45.72)
		)
		(stroke
			(width 0)
			(type default)
		)
	)
	(wire
		(pts
			(xy 344.17 218.44) (xy 346.71 220.98)
		)
		(stroke
			(width 0)
			(type default)
		)
	)
	(wire
		(pts
			(xy 317.5 156.21) (xy 316.23 156.21)
		)
		(stroke
			(width 0)
			(type default)
		)
	)
	(wire
		(pts
			(xy 322.58 104.14) (xy 322.58 110.49)
		)
		(stroke
			(width 0)
			(type default)
		)
	)
	(wire
		(pts
			(xy 351.79 55.88) (xy 347.98 55.88)
		)
		(stroke
			(width 0)
			(type default)
		)
	)
	(wire
		(pts
			(xy 43.18 190.5) (xy 43.18 191.77)
		)
		(stroke
			(width 0)
			(type default)
		)
	)
	(wire
		(pts
			(xy 260.35 104.14) (xy 280.67 104.14)
		)
		(stroke
			(width 0)
			(type default)
		)
	)
	(wire
		(pts
			(xy 73.66 85.09) (xy 127 85.09)
		)
		(stroke
			(width 0)
			(type default)
		)
	)
	(bus
		(pts
			(xy 72.39 73.66) (xy 72.39 76.2)
		)
		(stroke
			(width 0)
			(type default)
		)
	)
	(wire
		(pts
			(xy 58.42 49.53) (xy 68.58 49.53)
		)
		(stroke
			(width 0)
			(type default)
		)
	)
	(wire
		(pts
			(xy 350.52 195.58) (xy 351.79 195.58)
		)
		(stroke
			(width 0)
			(type default)
		)
	)
	(wire
		(pts
			(xy 148.59 237.49) (xy 148.59 241.3)
		)
		(stroke
			(width 0)
			(type default)
		)
	)
	(wire
		(pts
			(xy 110.49 72.39) (xy 127 72.39)
		)
		(stroke
			(width 0)
			(type default)
		)
	)
	(wire
		(pts
			(xy 260.35 190.5) (xy 323.85 190.5)
		)
		(stroke
			(width 0)
			(type default)
		)
	)
	(wire
		(pts
			(xy 260.35 213.36) (xy 284.48 213.36)
		)
		(stroke
			(width 0)
			(type default)
		)
	)
	(wire
		(pts
			(xy 346.71 88.9) (xy 351.79 88.9)
		)
		(stroke
			(width 0)
			(type default)
		)
	)
	(wire
		(pts
			(xy 260.35 60.96) (xy 314.96 60.96)
		)
		(stroke
			(width 0)
			(type default)
		)
	)
	(wire
		(pts
			(xy 17.78 58.42) (xy 17.78 59.69)
		)
		(stroke
			(width 0)
			(type default)
		)
	)
	(wire
		(pts
			(xy 314.96 220.98) (xy 314.96 232.41)
		)
		(stroke
			(width 0)
			(type default)
		)
	)
	(wire
		(pts
			(xy 336.55 163.83) (xy 336.55 165.1)
		)
		(stroke
			(width 0)
			(type default)
		)
	)
	(wire
		(pts
			(xy 76.2 248.92) (xy 92.71 248.92)
		)
		(stroke
			(width 0)
			(type default)
		)
	)
	(wire
		(pts
			(xy 317.5 218.44) (xy 317.5 232.41)
		)
		(stroke
			(width 0)
			(type default)
		)
	)
	(wire
		(pts
			(xy 182.88 179.07) (xy 228.6 179.07)
		)
		(stroke
			(width 0)
			(type default)
		)
	)
	(wire
		(pts
			(xy 31.75 248.92) (xy 52.07 248.92)
		)
		(stroke
			(width 0)
			(type default)
		)
	)
	(wire
		(pts
			(xy 114.3 189.23) (xy 114.3 184.15)
		)
		(stroke
			(width 0)
			(type default)
		)
	)
	(wire
		(pts
			(xy 373.38 154.94) (xy 373.38 153.67)
		)
		(stroke
			(width 0)
			(type default)
		)
	)
	(wire
		(pts
			(xy 332.74 156.21) (xy 336.55 156.21)
		)
		(stroke
			(width 0)
			(type default)
		)
	)
	(wire
		(pts
			(xy 182.88 176.53) (xy 236.22 176.53)
		)
		(stroke
			(width 0)
			(type default)
		)
	)
	(wire
		(pts
			(xy 182.88 116.84) (xy 200.66 116.84)
		)
		(stroke
			(width 0)
			(type default)
		)
	)
	(wire
		(pts
			(xy 207.01 261.62) (xy 207.01 265.43)
		)
		(stroke
			(width 0)
			(type default)
		)
	)
	(wire
		(pts
			(xy 151.13 260.35) (xy 152.4 260.35)
		)
		(stroke
			(width 0)
			(type default)
		)
	)
	(wire
		(pts
			(xy 332.74 153.67) (xy 346.71 153.67)
		)
		(stroke
			(width 0)
			(type default)
		)
	)
	(wire
		(pts
			(xy 182.88 121.92) (xy 200.66 121.92)
		)
		(stroke
			(width 0)
			(type default)
		)
	)
	(wire
		(pts
			(xy 54.61 271.78) (xy 76.2 271.78)
		)
		(stroke
			(width 0)
			(type default)
		)
	)
	(wire
		(pts
			(xy 101.6 74.93) (xy 127 74.93)
		)
		(stroke
			(width 0)
			(type default)
		)
	)
	(polyline
		(pts
			(xy 254 284.48) (xy 254 209.55)
		)
		(stroke
			(width 0)
			(type default)
		)
	)
	(wire
		(pts
			(xy 83.82 243.84) (xy 92.71 243.84)
		)
		(stroke
			(width 0)
			(type default)
		)
	)
	(bus
		(pts
			(xy 72.39 78.74) (xy 72.39 81.28)
		)
		(stroke
			(width 0)
			(type default)
		)
	)
	(wire
		(pts
			(xy 320.04 228.6) (xy 320.04 232.41)
		)
		(stroke
			(width 0)
			(type default)
		)
	)
	(wire
		(pts
			(xy 285.75 210.82) (xy 341.63 210.82)
		)
		(stroke
			(width 0)
			(type default)
		)
	)
	(wire
		(pts
			(xy 193.04 148.59) (xy 201.93 148.59)
		)
		(stroke
			(width 0)
			(type default)
		)
	)
	(wire
		(pts
			(xy 226.06 265.43) (xy 226.06 266.7)
		)
		(stroke
			(width 0)
			(type default)
		)
	)
	(wire
		(pts
			(xy 182.88 91.44) (xy 200.66 91.44)
		)
		(stroke
			(width 0)
			(type default)
		)
	)
	(bus
		(pts
			(xy 96.52 134.62) (xy 99.06 134.62)
		)
		(stroke
			(width 0)
			(type default)
		)
	)
	(wire
		(pts
			(xy 350.52 241.3) (xy 351.79 241.3)
		)
		(stroke
			(width 0)
			(type default)
		)
	)
	(wire
		(pts
			(xy 58.42 41.91) (xy 58.42 43.18)
		)
		(stroke
			(width 0)
			(type default)
		)
	)
	(bus
		(pts
			(xy 72.39 76.2) (xy 72.39 78.74)
		)
		(stroke
			(width 0)
			(type default)
		)
	)
	(wire
		(pts
			(xy 71.12 148.59) (xy 80.01 148.59)
		)
		(stroke
			(width 0)
			(type default)
		)
	)
	(wire
		(pts
			(xy 373.38 160.02) (xy 373.38 161.29)
		)
		(stroke
			(width 0)
			(type default)
		)
	)
	(wire
		(pts
			(xy 27.94 185.42) (xy 54.61 185.42)
		)
		(stroke
			(width 0)
			(type default)
		)
	)
	(wire
		(pts
			(xy 316.23 182.88) (xy 351.79 182.88)
		)
		(stroke
			(width 0)
			(type default)
		)
	)
	(wire
		(pts
			(xy 193.04 158.75) (xy 201.93 158.75)
		)
		(stroke
			(width 0)
			(type default)
		)
	)
	(wire
		(pts
			(xy 99.06 59.69) (xy 99.06 60.96)
		)
		(stroke
			(width 0)
			(type default)
		)
	)
	(wire
		(pts
			(xy 73.66 74.93) (xy 96.52 74.93)
		)
		(stroke
			(width 0)
			(type default)
		)
	)
	(wire
		(pts
			(xy 285.75 226.06) (xy 322.58 226.06)
		)
		(stroke
			(width 0)
			(type default)
		)
	)
	(wire
		(pts
			(xy 182.88 88.9) (xy 200.66 88.9)
		)
		(stroke
			(width 0)
			(type default)
		)
	)
	(wire
		(pts
			(xy 201.93 151.13) (xy 201.93 148.59)
		)
		(stroke
			(width 0)
			(type default)
		)
	)
	(wire
		(pts
			(xy 344.17 99.06) (xy 346.71 96.52)
		)
		(stroke
			(width 0)
			(type default)
		)
	)
	(wire
		(pts
			(xy 88.9 41.91) (xy 88.9 43.18)
		)
		(stroke
			(width 0)
			(type default)
		)
	)
	(wire
		(pts
			(xy 289.56 91.44) (xy 339.09 91.44)
		)
		(stroke
			(width 0)
			(type default)
		)
	)
	(wire
		(pts
			(xy 327.66 110.49) (xy 331.47 110.49)
		)
		(stroke
			(width 0)
			(type default)
		)
	)
	(wire
		(pts
			(xy 99.06 67.31) (xy 99.06 66.04)
		)
		(stroke
			(width 0)
			(type default)
		)
	)
	(wire
		(pts
			(xy 260.35 203.2) (xy 336.55 203.2)
		)
		(stroke
			(width 0)
			(type default)
		)
	)
	(wire
		(pts
			(xy 99.06 49.53) (xy 99.06 48.26)
		)
		(stroke
			(width 0)
			(type default)
		)
	)
	(wire
		(pts
			(xy 101.6 139.7) (xy 116.84 139.7)
		)
		(stroke
			(width 0)
			(type default)
		)
	)
	(wire
		(pts
			(xy 167.64 265.43) (xy 167.64 266.7)
		)
		(stroke
			(width 0)
			(type default)
		)
	)
	(wire
		(pts
			(xy 27.94 93.98) (xy 27.94 95.25)
		)
		(stroke
			(width 0)
			(type default)
		)
	)
	(wire
		(pts
			(xy 228.6 196.85) (xy 228.6 195.58)
		)
		(stroke
			(width 0)
			(type default)
		)
	)
	(wire
		(pts
			(xy 318.77 34.29) (xy 317.5 34.29)
		)
		(stroke
			(width 0)
			(type default)
		)
	)
	(wire
		(pts
			(xy 374.65 33.02) (xy 374.65 31.75)
		)
		(stroke
			(width 0)
			(type default)
		)
	)
	(wire
		(pts
			(xy 308.61 21.59) (xy 308.61 22.86)
		)
		(stroke
			(width 0)
			(type default)
		)
	)
	(wire
		(pts
			(xy 60.96 226.06) (xy 66.04 226.06)
		)
		(stroke
			(width 0)
			(type default)
		)
	)
	(wire
		(pts
			(xy 182.88 186.69) (xy 198.12 186.69)
		)
		(stroke
			(width 0)
			(type default)
		)
	)
	(wire
		(pts
			(xy 350.52 243.84) (xy 350.52 241.3)
		)
		(stroke
			(width 0)
			(type default)
		)
	)
	(wire
		(pts
			(xy 29.21 49.53) (xy 38.1 49.53)
		)
		(stroke
			(width 0)
			(type default)
		)
	)
	(wire
		(pts
			(xy 182.88 161.29) (xy 187.96 161.29)
		)
		(stroke
			(width 0)
			(type default)
		)
	)
	(wire
		(pts
			(xy 334.01 158.75) (xy 334.01 163.83)
		)
		(stroke
			(width 0)
			(type default)
		)
	)
	(wire
		(pts
			(xy 88.9 59.69) (xy 99.06 59.69)
		)
		(stroke
			(width 0)
			(type default)
		)
	)
	(wire
		(pts
			(xy 346.71 177.8) (xy 351.79 177.8)
		)
		(stroke
			(width 0)
			(type default)
		)
	)
	(wire
		(pts
			(xy 207.01 231.14) (xy 210.82 231.14)
		)
		(stroke
			(width 0)
			(type default)
		)
	)
	(wire
		(pts
			(xy 350.52 160.02) (xy 350.52 161.29)
		)
		(stroke
			(width 0)
			(type default)
		)
	)
	(wire
		(pts
			(xy 322.58 53.34) (xy 322.58 71.12)
		)
		(stroke
			(width 0)
			(type default)
		)
	)
	(wire
		(pts
			(xy 223.52 231.14) (xy 226.06 231.14)
		)
		(stroke
			(width 0)
			(type default)
		)
	)
	(wire
		(pts
			(xy 350.52 243.84) (xy 351.79 243.84)
		)
		(stroke
			(width 0)
			(type default)
		)
	)
	(wire
		(pts
			(xy 71.12 226.06) (xy 74.93 226.06)
		)
		(stroke
			(width 0)
			(type default)
		)
	)
	(wire
		(pts
			(xy 54.61 279.4) (xy 83.82 279.4)
		)
		(stroke
			(width 0)
			(type default)
		)
	)
	(wire
		(pts
			(xy 148.59 265.43) (xy 151.13 265.43)
		)
		(stroke
			(width 0)
			(type default)
		)
	)
	(wire
		(pts
			(xy 317.5 63.5) (xy 351.79 63.5)
		)
		(stroke
			(width 0)
			(type default)
		)
	)
	(wire
		(pts
			(xy 350.52 73.66) (xy 351.79 73.66)
		)
		(stroke
			(width 0)
			(type default)
		)
	)
	(wire
		(pts
			(xy 114.3 184.15) (xy 115.57 184.15)
		)
		(stroke
			(width 0)
			(type default)
		)
	)
	(wire
		(pts
			(xy 182.88 143.51) (xy 187.96 143.51)
		)
		(stroke
			(width 0)
			(type default)
		)
	)
	(polyline
		(pts
			(xy 254 209.55) (xy 137.16 209.55)
		)
		(stroke
			(width 0)
			(type default)
		)
	)
	(wire
		(pts
			(xy 182.88 181.61) (xy 213.36 181.61)
		)
		(stroke
			(width 0)
			(type default)
		)
	)
	(wire
		(pts
			(xy 148.59 231.14) (xy 148.59 232.41)
		)
		(stroke
			(width 0)
			(type default)
		)
	)
	(wire
		(pts
			(xy 334.01 34.29) (xy 337.82 34.29)
		)
		(stroke
			(width 0)
			(type default)
		)
	)
	(wire
		(pts
			(xy 48.26 67.31) (xy 48.26 66.04)
		)
		(stroke
			(width 0)
			(type default)
		)
	)
	(wire
		(pts
			(xy 226.06 260.35) (xy 251.46 260.35)
		)
		(stroke
			(width 0)
			(type default)
		)
	)
	(wire
		(pts
			(xy 308.61 21.59) (xy 317.5 21.59)
		)
		(stroke
			(width 0)
			(type default)
		)
	)
	(wire
		(pts
			(xy 114.3 127) (xy 127 127)
		)
		(stroke
			(width 0)
			(type default)
		)
	)
	(wire
		(pts
			(xy 209.55 236.22) (xy 209.55 241.3)
		)
		(stroke
			(width 0)
			(type default)
		)
	)
	(wire
		(pts
			(xy 182.88 127) (xy 200.66 127)
		)
		(stroke
			(width 0)
			(type default)
		)
	)
	(wire
		(pts
			(xy 165.1 231.14) (xy 167.64 231.14)
		)
		(stroke
			(width 0)
			(type default)
		)
	)
	(wire
		(pts
			(xy 346.71 153.67) (xy 346.71 177.8)
		)
		(stroke
			(width 0)
			(type default)
		)
	)
	(wire
		(pts
			(xy 17.78 49.53) (xy 17.78 48.26)
		)
		(stroke
			(width 0)
			(type default)
		)
	)
	(wire
		(pts
			(xy 223.52 265.43) (xy 226.06 265.43)
		)
		(stroke
			(width 0)
			(type default)
		)
	)
	(wire
		(pts
			(xy 52.07 246.38) (xy 31.75 246.38)
		)
		(stroke
			(width 0)
			(type default)
		)
	)
	(wire
		(pts
			(xy 346.71 218.44) (xy 351.79 218.44)
		)
		(stroke
			(width 0)
			(type default)
		)
	)
	(wire
		(pts
			(xy 182.88 151.13) (xy 187.96 151.13)
		)
		(stroke
			(width 0)
			(type default)
		)
	)
	(wire
		(pts
			(xy 337.82 34.29) (xy 337.82 35.56)
		)
		(stroke
			(width 0)
			(type default)
		)
	)
	(wire
		(pts
			(xy 316.23 176.53) (xy 316.23 182.88)
		)
		(stroke
			(width 0)
			(type default)
		)
	)
	(wire
		(pts
			(xy 339.09 91.44) (xy 339.09 110.49)
		)
		(stroke
			(width 0)
			(type default)
		)
	)
	(wire
		(pts
			(xy 370.84 31.75) (xy 374.65 31.75)
		)
		(stroke
			(width 0)
			(type default)
		)
	)
	(wire
		(pts
			(xy 236.22 171.45) (xy 236.22 176.53)
		)
		(stroke
			(width 0)
			(type default)
		)
	)
	(wire
		(pts
			(xy 165.1 241.3) (xy 167.64 241.3)
		)
		(stroke
			(width 0)
			(type default)
		)
	)
	(wire
		(pts
			(xy 260.35 193.04) (xy 321.31 193.04)
		)
		(stroke
			(width 0)
			(type default)
		)
	)
	(wire
		(pts
			(xy 76.2 248.92) (xy 76.2 271.78)
		)
		(stroke
			(width 0)
			(type default)
		)
	)
	(bus
		(pts
			(xy 68.58 82.55) (xy 71.12 82.55)
		)
		(stroke
			(width 0)
			(type default)
		)
	)
	(wire
		(pts
			(xy 350.52 153.67) (xy 350.52 154.94)
		)
		(stroke
			(width 0)
			(type default)
		)
	)
	(wire
		(pts
			(xy 213.36 196.85) (xy 213.36 195.58)
		)
		(stroke
			(width 0)
			(type default)
		)
	)
	(wire
		(pts
			(xy 339.09 213.36) (xy 351.79 213.36)
		)
		(stroke
			(width 0)
			(type default)
		)
	)
	(wire
		(pts
			(xy 165.1 236.22) (xy 167.64 236.22)
		)
		(stroke
			(width 0)
			(type default)
		)
	)
	(wire
		(pts
			(xy 344.17 203.2) (xy 346.71 205.74)
		)
		(stroke
			(width 0)
			(type default)
		)
	)
	(wire
		(pts
			(xy 99.06 59.69) (xy 109.22 59.69)
		)
		(stroke
			(width 0)
			(type default)
		)
	)
	(wire
		(pts
			(xy 91.44 256.54) (xy 92.71 256.54)
		)
		(stroke
			(width 0)
			(type default)
		)
	)
	(wire
		(pts
			(xy 312.42 54.61) (xy 312.42 53.34)
		)
		(stroke
			(width 0)
			(type default)
		)
	)
	(wire
		(pts
			(xy 205.74 184.15) (xy 205.74 190.5)
		)
		(stroke
			(width 0)
			(type default)
		)
	)
	(wire
		(pts
			(xy 43.18 198.12) (xy 43.18 196.85)
		)
		(stroke
			(width 0)
			(type default)
		)
	)
	(wire
		(pts
			(xy 78.74 41.91) (xy 88.9 41.91)
		)
		(stroke
			(width 0)
			(type default)
		)
	)
	(wire
		(pts
			(xy 48.26 49.53) (xy 58.42 49.53)
		)
		(stroke
			(width 0)
			(type default)
		)
	)
	(wire
		(pts
			(xy 332.74 158.75) (xy 334.01 158.75)
		)
		(stroke
			(width 0)
			(type default)
		)
	)
	(wire
		(pts
			(xy 73.66 82.55) (xy 99.06 82.55)
		)
		(stroke
			(width 0)
			(type default)
		)
	)
	(wire
		(pts
			(xy 231.14 255.27) (xy 234.95 255.27)
		)
		(stroke
			(width 0)
			(type default)
		)
	)
	(wire
		(pts
			(xy 118.11 67.31) (xy 127 67.31)
		)
		(stroke
			(width 0)
			(type default)
		)
	)
	(wire
		(pts
			(xy 182.88 101.6) (xy 208.28 101.6)
		)
		(stroke
			(width 0)
			(type default)
		)
	)
	(wire
		(pts
			(xy 314.96 60.96) (xy 351.79 60.96)
		)
		(stroke
			(width 0)
			(type default)
		)
	)
	(wire
		(pts
			(xy 104.14 77.47) (xy 127 77.47)
		)
		(stroke
			(width 0)
			(type default)
		)
	)
	(wire
		(pts
			(xy 285.75 104.14) (xy 322.58 104.14)
		)
		(stroke
			(width 0)
			(type default)
		)
	)
	(wire
		(pts
			(xy 109.22 59.69) (xy 109.22 60.96)
		)
		(stroke
			(width 0)
			(type default)
		)
	)
	(polyline
		(pts
			(xy 12.7 209.55) (xy 137.16 209.55)
		)
		(stroke
			(width 0)
			(type default)
		)
	)
	(wire
		(pts
			(xy 182.88 114.3) (xy 200.66 114.3)
		)
		(stroke
			(width 0)
			(type default)
		)
	)
	(wire
		(pts
			(xy 43.18 190.5) (xy 54.61 190.5)
		)
		(stroke
			(width 0)
			(type default)
		)
	)
	(wire
		(pts
			(xy 307.34 142.24) (xy 307.34 143.51)
		)
		(stroke
			(width 0)
			(type default)
		)
	)
	(wire
		(pts
			(xy 307.34 143.51) (xy 316.23 143.51)
		)
		(stroke
			(width 0)
			(type default)
		)
	)
	(wire
		(pts
			(xy 350.52 190.5) (xy 350.52 195.58)
		)
		(stroke
			(width 0)
			(type default)
		)
	)
	(wire
		(pts
			(xy 172.72 255.27) (xy 176.53 255.27)
		)
		(stroke
			(width 0)
			(type default)
		)
	)
	(wire
		(pts
			(xy 182.88 129.54) (xy 200.66 129.54)
		)
		(stroke
			(width 0)
			(type default)
		)
	)
	(wire
		(pts
			(xy 48.26 49.53) (xy 48.26 48.26)
		)
		(stroke
			(width 0)
			(type default)
		)
	)
	(wire
		(pts
			(xy 17.78 40.64) (xy 17.78 41.91)
		)
		(stroke
			(width 0)
			(type default)
		)
	)
	(wire
		(pts
			(xy 322.58 71.12) (xy 347.98 71.12)
		)
		(stroke
			(width 0)
			(type default)
		)
	)
	(wire
		(pts
			(xy 337.82 40.64) (xy 337.82 41.91)
		)
		(stroke
			(width 0)
			(type default)
		)
	)
	(wire
		(pts
			(xy 318.77 185.42) (xy 351.79 185.42)
		)
		(stroke
			(width 0)
			(type default)
		)
	)
	(wire
		(pts
			(xy 101.6 148.59) (xy 121.92 148.59)
		)
		(stroke
			(width 0)
			(type default)
		)
	)
	(wire
		(pts
			(xy 316.23 153.67) (xy 317.5 153.67)
		)
		(stroke
			(width 0)
			(type default)
		)
	)
	(wire
		(pts
			(xy 48.26 59.69) (xy 58.42 59.69)
		)
		(stroke
			(width 0)
			(type default)
		)
	)
	(wire
		(pts
			(xy 31.75 256.54) (xy 52.07 256.54)
		)
		(stroke
			(width 0)
			(type default)
		)
	)
	(wire
		(pts
			(xy 193.04 146.05) (xy 199.39 146.05)
		)
		(stroke
			(width 0)
			(type default)
		)
	)
	(wire
		(pts
			(xy 260.35 63.5) (xy 317.5 63.5)
		)
		(stroke
			(width 0)
			(type default)
		)
	)
	(wire
		(pts
			(xy 114.3 160.02) (xy 127 160.02)
		)
		(stroke
			(width 0)
			(type default)
		)
	)
	(wire
		(pts
			(xy 17.78 66.04) (xy 17.78 67.31)
		)
		(stroke
			(width 0)
			(type default)
		)
	)
	(wire
		(pts
			(xy 35.56 187.96) (xy 54.61 187.96)
		)
		(stroke
			(width 0)
			(type default)
		)
	)
	(wire
		(pts
			(xy 38.1 59.69) (xy 48.26 59.69)
		)
		(stroke
			(width 0)
			(type default)
		)
	)
	(wire
		(pts
			(xy 346.71 83.82) (xy 351.79 83.82)
		)
		(stroke
			(width 0)
			(type default)
		)
	)
	(wire
		(pts
			(xy 260.35 182.88) (xy 316.23 182.88)
		)
		(stroke
			(width 0)
			(type default)
		)
	)
	(wire
		(pts
			(xy 210.82 265.43) (xy 209.55 265.43)
		)
		(stroke
			(width 0)
			(type default)
		)
	)
	(wire
		(pts
			(xy 29.21 49.53) (xy 29.21 48.26)
		)
		(stroke
			(width 0)
			(type default)
		)
	)
	(wire
		(pts
			(xy 38.1 41.91) (xy 38.1 43.18)
		)
		(stroke
			(width 0)
			(type default)
		)
	)
	(wire
		(pts
			(xy 17.78 50.8) (xy 17.78 49.53)
		)
		(stroke
			(width 0)
			(type default)
		)
	)
	(wire
		(pts
			(xy 314.96 53.34) (xy 314.96 60.96)
		)
		(stroke
			(width 0)
			(type default)
		)
	)
	(wire
		(pts
			(xy 68.58 67.31) (xy 78.74 67.31)
		)
		(stroke
			(width 0)
			(type default)
		)
	)
	(wire
		(pts
			(xy 260.35 220.98) (xy 314.96 220.98)
		)
		(stroke
			(width 0)
			(type default)
		)
	)
	(wire
		(pts
			(xy 336.55 156.21) (xy 336.55 157.48)
		)
		(stroke
			(width 0)
			(type default)
		)
	)
	(wire
		(pts
			(xy 215.9 63.5) (xy 228.6 63.5)
		)
		(stroke
			(width 0)
			(type default)
		)
	)
	(wire
		(pts
			(xy 341.63 210.82) (xy 351.79 210.82)
		)
		(stroke
			(width 0)
			(type default)
		)
	)
	(wire
		(pts
			(xy 339.09 213.36) (xy 339.09 232.41)
		)
		(stroke
			(width 0)
			(type default)
		)
	)
	(wire
		(pts
			(xy 201.93 148.59) (xy 201.93 142.24)
		)
		(stroke
			(width 0)
			(type default)
		)
	)
	(wire
		(pts
			(xy 317.5 218.44) (xy 344.17 218.44)
		)
		(stroke
			(width 0)
			(type default)
		)
	)
	(wire
		(pts
			(xy 127 179.07) (xy 124.46 179.07)
		)
		(stroke
			(width 0)
			(type default)
		)
	)
	(wire
		(pts
			(xy 209.55 260.35) (xy 209.55 265.43)
		)
		(stroke
			(width 0)
			(type default)
		)
	)
	(wire
		(pts
			(xy 346.71 203.2) (xy 351.79 203.2)
		)
		(stroke
			(width 0)
			(type default)
		)
	)
	(wire
		(pts
			(xy 60.96 224.79) (xy 60.96 226.06)
		)
		(stroke
			(width 0)
			(type default)
		)
	)
	(bus
		(pts
			(xy 49.53 269.24) (xy 52.07 269.24)
		)
		(stroke
			(width 0)
			(type default)
		)
	)
	(wire
		(pts
			(xy 27.94 95.25) (xy 27.94 96.52)
		)
		(stroke
			(width 0)
			(type default)
		)
	)
	(wire
		(pts
			(xy 336.55 81.28) (xy 344.17 81.28)
		)
		(stroke
			(width 0)
			(type default)
		)
	)
	(wire
		(pts
			(xy 182.88 83.82) (xy 200.66 83.82)
		)
		(stroke
			(width 0)
			(type default)
		)
	)
	(wire
		(pts
			(xy 27.94 128.27) (xy 27.94 130.81)
		)
		(stroke
			(width 0)
			(type default)
		)
	)
	(wire
		(pts
			(xy 48.26 67.31) (xy 58.42 67.31)
		)
		(stroke
			(width 0)
			(type default)
		)
	)
	(wire
		(pts
			(xy 88.9 67.31) (xy 88.9 66.04)
		)
		(stroke
			(width 0)
			(type default)
		)
	)
	(wire
		(pts
			(xy 87.63 233.68) (xy 87.63 226.06)
		)
		(stroke
			(width 0)
			(type default)
		)
	)
	(wire
		(pts
			(xy 320.04 106.68) (xy 351.79 106.68)
		)
		(stroke
			(width 0)
			(type default)
		)
	)
	(wire
		(pts
			(xy 351.79 68.58) (xy 350.52 68.58)
		)
		(stroke
			(width 0)
			(type default)
		)
	)
	(wire
		(pts
			(xy 151.13 236.22) (xy 152.4 236.22)
		)
		(stroke
			(width 0)
			(type default)
		)
	)
	(wire
		(pts
			(xy 35.56 198.12) (xy 35.56 196.85)
		)
		(stroke
			(width 0)
			(type default)
		)
	)
	(wire
		(pts
			(xy 207.01 255.27) (xy 210.82 255.27)
		)
		(stroke
			(width 0)
			(type default)
		)
	)
	(wire
		(pts
			(xy 318.77 176.53) (xy 318.77 185.42)
		)
		(stroke
			(width 0)
			(type default)
		)
	)
	(wire
		(pts
			(xy 337.82 41.91) (xy 337.82 43.18)
		)
		(stroke
			(width 0)
			(type default)
		)
	)
	(wire
		(pts
			(xy 208.28 63.5) (xy 210.82 63.5)
		)
		(stroke
			(width 0)
			(type default)
		)
	)
	(wire
		(pts
			(xy 334.01 205.74) (xy 334.01 232.41)
		)
		(stroke
			(width 0)
			(type default)
		)
	)
	(wire
		(pts
			(xy 314.96 99.06) (xy 344.17 99.06)
		)
		(stroke
			(width 0)
			(type default)
		)
	)
	(wire
		(pts
			(xy 193.04 143.51) (xy 199.39 143.51)
		)
		(stroke
			(width 0)
			(type default)
		)
	)
	(wire
		(pts
			(xy 317.5 96.52) (xy 344.17 96.52)
		)
		(stroke
			(width 0)
			(type default)
		)
	)
	(wire
		(pts
			(xy 321.31 193.04) (xy 347.98 193.04)
		)
		(stroke
			(width 0)
			(type default)
		)
	)
	(wire
		(pts
			(xy 213.36 190.5) (xy 213.36 181.61)
		)
		(stroke
			(width 0)
			(type default)
		)
	)
	(wire
		(pts
			(xy 182.88 148.59) (xy 187.96 148.59)
		)
		(stroke
			(width 0)
			(type default)
		)
	)
	(wire
		(pts
			(xy 182.88 111.76) (xy 200.66 111.76)
		)
		(stroke
			(width 0)
			(type default)
		)
	)
	(wire
		(pts
			(xy 260.35 91.44) (xy 284.48 91.44)
		)
		(stroke
			(width 0)
			(type default)
		)
	)
	(wire
		(pts
			(xy 199.39 143.51) (xy 199.39 146.05)
		)
		(stroke
			(width 0)
			(type default)
		)
	)
	(wire
		(pts
			(xy 127 176.53) (xy 92.71 176.53)
		)
		(stroke
			(width 0)
			(type default)
		)
	)
	(wire
		(pts
			(xy 210.82 241.3) (xy 209.55 241.3)
		)
		(stroke
			(width 0)
			(type default)
		)
	)
	(wire
		(pts
			(xy 182.88 66.04) (xy 200.66 66.04)
		)
		(stroke
			(width 0)
			(type default)
		)
	)
	(wire
		(pts
			(xy 236.22 196.85) (xy 236.22 195.58)
		)
		(stroke
			(width 0)
			(type default)
		)
	)
	(wire
		(pts
			(xy 350.52 245.11) (xy 350.52 243.84)
		)
		(stroke
			(width 0)
			(type default)
		)
	)
	(wire
		(pts
			(xy 109.22 41.91) (xy 123.19 41.91)
		)
		(stroke
			(width 0)
			(type default)
		)
	)
	(wire
		(pts
			(xy 92.71 163.83) (xy 100.33 163.83)
		)
		(stroke
			(width 0)
			(type default)
		)
	)
	(wire
		(pts
			(xy 99.06 41.91) (xy 99.06 43.18)
		)
		(stroke
			(width 0)
			(type default)
		)
	)
	(wire
		(pts
			(xy 99.06 67.31) (xy 109.22 67.31)
		)
		(stroke
			(width 0)
			(type default)
		)
	)
	(wire
		(pts
			(xy 121.92 154.94) (xy 127 154.94)
		)
		(stroke
			(width 0)
			(type default)
		)
	)
	(wire
		(pts
			(xy 27.94 184.15) (xy 27.94 185.42)
		)
		(stroke
			(width 0)
			(type default)
		)
	)
	(wire
		(pts
			(xy 38.1 67.31) (xy 48.26 67.31)
		)
		(stroke
			(width 0)
			(type default)
		)
	)
	(wire
		(pts
			(xy 58.42 49.53) (xy 58.42 48.26)
		)
		(stroke
			(width 0)
			(type default)
		)
	)
	(wire
		(pts
			(xy 240.03 255.27) (xy 251.46 255.27)
		)
		(stroke
			(width 0)
			(type default)
		)
	)
	(wire
		(pts
			(xy 38.1 66.04) (xy 38.1 67.31)
		)
		(stroke
			(width 0)
			(type default)
		)
	)
	(wire
		(pts
			(xy 107.95 170.18) (xy 107.95 171.45)
		)
		(stroke
			(width 0)
			(type default)
		)
	)
	(wire
		(pts
			(xy 107.95 165.1) (xy 107.95 163.83)
		)
		(stroke
			(width 0)
			(type default)
		)
	)
	(wire
		(pts
			(xy 370.84 29.21) (xy 370.84 31.75)
		)
		(stroke
			(width 0)
			(type default)
		)
	)
	(wire
		(pts
			(xy 346.71 205.74) (xy 351.79 205.74)
		)
		(stroke
			(width 0)
			(type default)
		)
	)
	(wire
		(pts
			(xy 321.31 176.53) (xy 321.31 193.04)
		)
		(stroke
			(width 0)
			(type default)
		)
	)
	(wire
		(pts
			(xy 240.03 231.14) (xy 251.46 231.14)
		)
		(stroke
			(width 0)
			(type default)
		)
	)
	(wire
		(pts
			(xy 336.55 162.56) (xy 336.55 163.83)
		)
		(stroke
			(width 0)
			(type default)
		)
	)
	(wire
		(pts
			(xy 31.75 251.46) (xy 52.07 251.46)
		)
		(stroke
			(width 0)
			(type default)
		)
	)
	(bus
		(pts
			(xy 53.34 275.59) (xy 53.34 278.13)
		)
		(stroke
			(width 0)
			(type default)
		)
	)
	(wire
		(pts
			(xy 320.04 68.58) (xy 350.52 68.58)
		)
		(stroke
			(width 0)
			(type default)
		)
	)
	(wire
		(pts
			(xy 99.06 49.53) (xy 109.22 49.53)
		)
		(stroke
			(width 0)
			(type default)
		)
	)
	(wire
		(pts
			(xy 260.35 205.74) (xy 334.01 205.74)
		)
		(stroke
			(width 0)
			(type default)
		)
	)
	(wire
		(pts
			(xy 151.13 260.35) (xy 151.13 265.43)
		)
		(stroke
			(width 0)
			(type default)
		)
	)
	(wire
		(pts
			(xy 223.52 241.3) (xy 226.06 241.3)
		)
		(stroke
			(width 0)
			(type default)
		)
	)
	(wire
		(pts
			(xy 127 62.23) (xy 123.19 62.23)
		)
		(stroke
			(width 0)
			(type default)
		)
	)
	(wire
		(pts
			(xy 327.66 110.49) (xy 327.66 114.3)
		)
		(stroke
			(width 0)
			(type default)
		)
	)
	(wire
		(pts
			(xy 182.88 81.28) (xy 200.66 81.28)
		)
		(stroke
			(width 0)
			(type default)
		)
	)
	(label "USBC4_CC_{2}"
		(at 260.35 185.42 0)
		(effects
			(font
				(size 1.27 1.27)
			)
			(justify left bottom)
		)
	)
	(label "USBC3_CC_{2}"
		(at 260.35 63.5 0)
		(effects
			(font
				(size 1.27 1.27)
			)
			(justify left bottom)
		)
	)
	(label "HUB_SPI_CE_N"
		(at 31.75 243.84 0)
		(effects
			(font
				(size 1.27 1.27)
			)
			(justify left bottom)
		)
	)
	(label "USBC4_CC_{1}"
		(at 251.46 231.14 180)
		(effects
			(font
				(size 1.27 1.27)
			)
			(justify right bottom)
		)
	)
	(label "USB2.D-"
		(at 74.93 87.63 0)
		(effects
			(font
				(size 1.27 1.27)
			)
			(justify left bottom)
		)
	)
	(label "DP2_DISCH"
		(at 114.3 99.06 0)
		(effects
			(font
				(size 1.27 1.27)
			)
			(justify left bottom)
		)
	)
	(label "HUB_SPI_CLK"
		(at 31.75 246.38 0)
		(effects
			(font
				(size 1.27 1.27)
			)
			(justify left bottom)
		)
	)
	(label "USBC4_VBUS"
		(at 228.6 63.5 180)
		(effects
			(font
				(size 1.27 1.27)
			)
			(justify right bottom)
		)
	)
	(label "USBC3_VBUS"
		(at 335.28 31.75 0)
		(effects
			(font
				(size 1.27 1.27)
			)
			(justify left bottom)
		)
	)
	(label "USBC3_TX_{2}-"
		(at 260.35 106.68 0)
		(effects
			(font
				(size 1.27 1.27)
			)
			(justify left bottom)
		)
	)
	(label "HUB_SPI_D1"
		(at 31.75 251.46 0)
		(effects
			(font
				(size 1.27 1.27)
			)
			(justify left bottom)
		)
	)
	(label "USBC3_CONN_TX1_N"
		(at 311.15 88.9 180)
		(effects
			(font
				(size 1.27 1.27)
			)
			(justify right bottom)
		)
	)
	(label "~{RESET}"
		(at 118.11 67.31 0)
		(effects
			(font
				(size 1.27 1.27)
			)
			(justify left bottom)
		)
	)
	(label "SPI_{HUB_DEBUG}.~{CS0}"
		(at 55.88 279.4 0)
		(effects
			(font
				(size 1.27 1.27)
			)
			(justify left bottom)
		)
	)
	(label "PRT_CTL2"
		(at 303.53 36.83 0)
		(effects
			(font
				(size 1.27 1.27)
			)
			(justify left bottom)
		)
	)
	(label "USBC4_CONN_TX2_P"
		(at 312.42 226.06 180)
		(effects
			(font
				(size 1.27 1.27)
			)
			(justify right bottom)
		)
	)
	(label "USBC4_RX_{2}+"
		(at 200.66 81.28 180)
		(effects
			(font
				(size 1.27 1.27)
			)
			(justify right bottom)
		)
	)
	(label "HUB_SPI_D2"
		(at 31.75 254 0)
		(effects
			(font
				(size 1.27 1.27)
			)
			(justify left bottom)
		)
	)
	(label "USBC3_RX_{2}-"
		(at 200.66 121.92 180)
		(effects
			(font
				(size 1.27 1.27)
			)
			(justify right bottom)
		)
	)
	(label "CFG_STRAP1"
		(at 114.3 160.02 0)
		(effects
			(font
				(size 1.27 1.27)
			)
			(justify left bottom)
		)
	)
	(label "USBC3_TX_{2}-"
		(at 200.66 127 180)
		(effects
			(font
				(size 1.27 1.27)
			)
			(justify right bottom)
		)
	)
	(label "DP1_DISCH"
		(at 114.3 101.6 0)
		(effects
			(font
				(size 1.27 1.27)
			)
			(justify left bottom)
		)
	)
	(label "CFG_STRAP3"
		(at 54.61 190.5 180)
		(effects
			(font
				(size 1.27 1.27)
			)
			(justify right bottom)
		)
	)
	(label "USBC4_RX_{1}-"
		(at 200.66 73.66 180)
		(effects
			(font
				(size 1.27 1.27)
			)
			(justify right bottom)
		)
	)
	(label "USBC4_VBUS"
		(at 334.01 153.67 0)
		(effects
			(font
				(size 1.27 1.27)
			)
			(justify left bottom)
		)
	)
	(label "USBC4_CC_{2}"
		(at 251.46 255.27 180)
		(effects
			(font
				(size 1.27 1.27)
			)
			(justify right bottom)
		)
	)
	(label "USBC3_CONN_TX1_P"
		(at 312.42 91.44 180)
		(effects
			(font
				(size 1.27 1.27)
			)
			(justify right bottom)
		)
	)
	(label "DP1_VCONN1"
		(at 114.3 93.98 0)
		(effects
			(font
				(size 1.27 1.27)
			)
			(justify left bottom)
		)
	)
	(label "USBC4_CC_{2}"
		(at 200.66 68.58 180)
		(effects
			(font
				(size 1.27 1.27)
			)
			(justify right bottom)
		)
	)
	(label "DP1_VCONN2"
		(at 251.46 260.35 180)
		(effects
			(font
				(size 1.27 1.27)
			)
			(justify right bottom)
		)
	)
	(label "USBC4_D-"
		(at 260.35 193.04 0)
		(effects
			(font
				(size 1.27 1.27)
			)
			(justify left bottom)
		)
	)
	(label "HUB_SPI_CLK"
		(at 185.42 173.99 0)
		(effects
			(font
				(size 1.27 1.27)
			)
			(justify left bottom)
		)
	)
	(label "I2C_{SYS}.SCL"
		(at 102.87 139.7 0)
		(effects
			(font
				(size 1.27 1.27)
			)
			(justify left bottom)
		)
	)
	(label "VBUS_MON_UP"
		(at 110.49 72.39 0)
		(effects
			(font
				(size 1.27 1.27)
			)
			(justify left bottom)
		)
	)
	(label "PRT_CTL1"
		(at 114.3 132.08 0)
		(effects
			(font
				(size 1.27 1.27)
			)
			(justify left bottom)
		)
	)
	(label "PRT_CTL4"
		(at 114.3 129.54 0)
		(effects
			(font
				(size 1.27 1.27)
			)
			(justify left bottom)
		)
	)
	(label "PRT_CTL2"
		(at 114.3 127 0)
		(effects
			(font
				(size 1.27 1.27)
			)
			(justify left bottom)
		)
	)
	(label "PRT_CTL3"
		(at 114.3 121.92 0)
		(effects
			(font
				(size 1.27 1.27)
			)
			(justify left bottom)
		)
	)
	(label "TEST1"
		(at 120.65 171.45 0)
		(effects
			(font
				(size 1.27 1.27)
			)
			(justify left bottom)
		)
	)
	(label "USBC3_RX_{1}-"
		(at 200.66 111.76 180)
		(effects
			(font
				(size 1.27 1.27)
			)
			(justify right bottom)
		)
	)
	(label "~{RESET}"
		(at 41.91 95.25 180)
		(effects
			(font
				(size 1.27 1.27)
			)
			(justify right bottom)
		)
	)
	(label "USBC3_D-"
		(at 200.66 132.08 180)
		(effects
			(font
				(size 1.27 1.27)
			)
			(justify right bottom)
		)
	)
	(label "USBC3_TX_{2}+"
		(at 260.35 104.14 0)
		(effects
			(font
				(size 1.27 1.27)
			)
			(justify left bottom)
		)
	)
	(label "USBC3_CC_{2}"
		(at 193.04 255.27 180)
		(effects
			(font
				(size 1.27 1.27)
			)
			(justify right bottom)
		)
	)
	(label "USBSS_TX_P"
		(at 110.49 74.93 0)
		(effects
			(font
				(size 1.27 1.27)
			)
			(justify left bottom)
		)
	)
	(label "USBC3_RX_{2}+"
		(at 200.66 119.38 180)
		(effects
			(font
				(size 1.27 1.27)
			)
			(justify right bottom)
		)
	)
	(label "USBSS_RX_P"
		(at 110.49 80.01 0)
		(effects
			(font
				(size 1.27 1.27)
			)
			(justify left bottom)
		)
	)
	(label "HUB_~{HOLD}"
		(at 80.01 241.3 0)
		(effects
			(font
				(size 1.27 1.27)
			)
			(justify left bottom)
		)
	)
	(label "USBC3_VBUS"
		(at 228.6 101.6 180)
		(effects
			(font
				(size 1.27 1.27)
			)
			(justify right bottom)
		)
	)
	(label "HUB_SPI_CE_N"
		(at 185.42 176.53 0)
		(effects
			(font
				(size 1.27 1.27)
			)
			(justify left bottom)
		)
	)
	(label "USBC3_D-"
		(at 260.35 71.12 0)
		(effects
			(font
				(size 1.27 1.27)
			)
			(justify left bottom)
		)
	)
	(label "SPI_{HUB_DEBUG}.MOSI"
		(at 55.88 274.32 0)
		(effects
			(font
				(size 1.27 1.27)
			)
			(justify left bottom)
		)
	)
	(label "USBC3_RX_{1}+"
		(at 200.66 109.22 180)
		(effects
			(font
				(size 1.27 1.27)
			)
			(justify right bottom)
		)
	)
	(label "USBC3_CC_{2}"
		(at 200.66 106.68 180)
		(effects
			(font
				(size 1.27 1.27)
			)
			(justify right bottom)
		)
	)
	(label "DP2_VCONN1"
		(at 193.04 236.22 180)
		(effects
			(font
				(size 1.27 1.27)
			)
			(justify right bottom)
		)
	)
	(label "USBC3_RX_{1}+"
		(at 260.35 81.28 0)
		(effects
			(font
				(size 1.27 1.27)
			)
			(justify left bottom)
		)
	)
	(label "USBSS2.TX+"
		(at 74.93 80.01 0)
		(effects
			(font
				(size 1.27 1.27)
			)
			(justify left bottom)
		)
	)
	(label "USBC3_CC_{1}"
		(at 200.66 104.14 180)
		(effects
			(font
				(size 1.27 1.27)
			)
			(justify right bottom)
		)
	)
	(label "TEST2"
		(at 120.65 173.99 0)
		(effects
			(font
				(size 1.27 1.27)
			)
			(justify left bottom)
		)
	)
	(label "VBUS_MON_UP"
		(at 49.53 128.27 180)
		(effects
			(font
				(size 1.27 1.27)
			)
			(justify right bottom)
		)
	)
	(label "CFG_STRAP3"
		(at 114.3 165.1 0)
		(effects
			(font
				(size 1.27 1.27)
			)
			(justify left bottom)
		)
	)
	(label "DP2_VCONN2"
		(at 193.04 260.35 180)
		(effects
			(font
				(size 1.27 1.27)
			)
			(justify right bottom)
		)
	)
	(label "USBC4_TX_{2}+"
		(at 260.35 226.06 0)
		(effects
			(font
				(size 1.27 1.27)
			)
			(justify left bottom)
		)
	)
	(label "CFG_STRAP2"
		(at 114.3 162.56 0)
		(effects
			(font
				(size 1.27 1.27)
			)
			(justify left bottom)
		)
	)
	(label "HUB_~{WP}"
		(at 72.39 254 180)
		(effects
			(font
				(size 1.27 1.27)
			)
			(justify right bottom)
		)
	)
	(label "USBC3_TX_{1}-"
		(at 260.35 91.44 0)
		(effects
			(font
				(size 1.27 1.27)
			)
			(justify left bottom)
		)
	)
	(label "HUB_SPI_D0"
		(at 31.75 248.92 0)
		(effects
			(font
				(size 1.27 1.27)
			)
			(justify left bottom)
		)
	)
	(label "USBC4_RX_{2}-"
		(at 200.66 83.82 180)
		(effects
			(font
				(size 1.27 1.27)
			)
			(justify right bottom)
		)
	)
	(label "USBC3_CC_{1}"
		(at 193.04 231.14 180)
		(effects
			(font
				(size 1.27 1.27)
			)
			(justify right bottom)
		)
	)
	(label "USBC4_TX_{2}+"
		(at 200.66 86.36 180)
		(effects
			(font
				(size 1.27 1.27)
			)
			(justify right bottom)
		)
	)
	(label "USBC3_ISET"
		(at 335.28 34.29 0)
		(effects
			(font
				(size 1.27 1.27)
			)
			(justify left bottom)
		)
	)
	(label "USBC4_TX_{1}+"
		(at 200.66 76.2 180)
		(effects
			(font
				(size 1.27 1.27)
			)
			(justify right bottom)
		)
	)
	(label "USBC4_CONN_TX1_P"
		(at 312.42 210.82 180)
		(effects
			(font
				(size 1.27 1.27)
			)
			(justify right bottom)
		)
	)
	(label "USBC4_RX_{2}-"
		(at 260.35 220.98 0)
		(effects
			(font
				(size 1.27 1.27)
			)
			(justify left bottom)
		)
	)
	(label "USBC4_TX_{2}-"
		(at 200.66 88.9 180)
		(effects
			(font
				(size 1.27 1.27)
			)
			(justify right bottom)
		)
	)
	(label "CFG_STRAP1"
		(at 54.61 185.42 180)
		(effects
			(font
				(size 1.27 1.27)
			)
			(justify right bottom)
		)
	)
	(label "DP2_VCONN2"
		(at 114.3 116.84 0)
		(effects
			(font
				(size 1.27 1.27)
			)
			(justify left bottom)
		)
	)
	(label "USBC4_RX_{1}+"
		(at 200.66 71.12 180)
		(effects
			(font
				(size 1.27 1.27)
			)
			(justify right bottom)
		)
	)
	(label "DP1_VCONN2"
		(at 114.3 96.52 0)
		(effects
			(font
				(size 1.27 1.27)
			)
			(justify left bottom)
		)
	)
	(label "USBC4_ISET"
		(at 334.01 156.21 0)
		(effects
			(font
				(size 1.27 1.27)
			)
			(justify left bottom)
		)
	)
	(label "USBSS_RX_N"
		(at 110.49 82.55 0)
		(effects
			(font
				(size 1.27 1.27)
			)
			(justify left bottom)
		)
	)
	(label "USBC3_RX_{2}+"
		(at 260.35 96.52 0)
		(effects
			(font
				(size 1.27 1.27)
			)
			(justify left bottom)
		)
	)
	(label "USBSS_TX_N"
		(at 110.49 77.47 0)
		(effects
			(font
				(size 1.27 1.27)
			)
			(justify left bottom)
		)
	)
	(label "USBC4_D-"
		(at 200.66 93.98 180)
		(effects
			(font
				(size 1.27 1.27)
			)
			(justify right bottom)
		)
	)
	(label "HUB_~{WP}"
		(at 80.01 238.76 0)
		(effects
			(font
				(size 1.27 1.27)
			)
			(justify left bottom)
		)
	)
	(label "USBSS2.RX+"
		(at 74.93 74.93 0)
		(effects
			(font
				(size 1.27 1.27)
			)
			(justify left bottom)
		)
	)
	(label "USBC3_CONN_TX2_N"
		(at 311.15 104.14 180)
		(effects
			(font
				(size 1.27 1.27)
			)
			(justify right bottom)
		)
	)
	(label "USBC4_TX_{1}+"
		(at 260.35 210.82 0)
		(effects
			(font
				(size 1.27 1.27)
			)
			(justify left bottom)
		)
	)
	(label "USBC4_TX_{1}-"
		(at 260.35 213.36 0)
		(effects
			(font
				(size 1.27 1.27)
			)
			(justify left bottom)
		)
	)
	(label "DP1_VCONN1"
		(at 251.46 236.22 180)
		(effects
			(font
				(size 1.27 1.27)
			)
			(justify right bottom)
		)
	)
	(label "USBC4_CC_{1}"
		(at 260.35 182.88 0)
		(effects
			(font
				(size 1.27 1.27)
			)
			(justify left bottom)
		)
	)
	(label "I2C_{SYS}.SDA"
		(at 102.87 137.16 0)
		(effects
			(font
				(size 1.27 1.27)
			)
			(justify left bottom)
		)
	)
	(label "HUB_SPI_D3"
		(at 196.85 186.69 180)
		(effects
			(font
				(size 1.27 1.27)
			)
			(justify right bottom)
		)
	)
	(label "HUB_~{HOLD}"
		(at 72.39 256.54 180)
		(effects
			(font
				(size 1.27 1.27)
			)
			(justify right bottom)
		)
	)
	(label "USBC3_VBUS_MON"
		(at 200.66 101.6 180)
		(effects
			(font
				(size 1.27 1.27)
			)
			(justify right bottom)
		)
	)
	(label "USBC3_D+"
		(at 200.66 129.54 180)
		(effects
			(font
				(size 1.27 1.27)
			)
			(justify right bottom)
		)
	)
	(label "HUB_SPI_D2"
		(at 196.85 184.15 180)
		(effects
			(font
				(size 1.27 1.27)
			)
			(justify right bottom)
		)
	)
	(label "SPI_{HUB_DEBUG}.SCK"
		(at 55.88 276.86 0)
		(effects
			(font
				(size 1.27 1.27)
			)
			(justify left bottom)
		)
	)
	(label "USBC4_RX_{1}+"
		(at 260.35 203.2 0)
		(effects
			(font
				(size 1.27 1.27)
			)
			(justify left bottom)
		)
	)
	(label "USBC3_TX_{1}+"
		(at 260.35 88.9 0)
		(effects
			(font
				(size 1.27 1.27)
			)
			(justify left bottom)
		)
	)
	(label "USBC4_TX_{2}-"
		(at 260.35 228.6 0)
		(effects
			(font
				(size 1.27 1.27)
			)
			(justify left bottom)
		)
	)
	(label "USBC4_D+"
		(at 260.35 190.5 0)
		(effects
			(font
				(size 1.27 1.27)
			)
			(justify left bottom)
		)
	)
	(label "HUB_SPI_D3"
		(at 31.75 256.54 0)
		(effects
			(font
				(size 1.27 1.27)
			)
			(justify left bottom)
		)
	)
	(label "USBC4_TX_{1}-"
		(at 200.66 78.74 180)
		(effects
			(font
				(size 1.27 1.27)
			)
			(justify right bottom)
		)
	)
	(label "HUB_SPI_D1"
		(at 196.85 181.61 180)
		(effects
			(font
				(size 1.27 1.27)
			)
			(justify right bottom)
		)
	)
	(label "USBSS2.RX-"
		(at 74.93 77.47 0)
		(effects
			(font
				(size 1.27 1.27)
			)
			(justify left bottom)
		)
	)
	(label "USBSS2.TX-"
		(at 74.93 82.55 0)
		(effects
			(font
				(size 1.27 1.27)
			)
			(justify left bottom)
		)
	)
	(label "USBC4_CONN_TX2_N"
		(at 312.42 228.6 180)
		(effects
			(font
				(size 1.27 1.27)
			)
			(justify right bottom)
		)
	)
	(label "USBC3_D+"
		(at 260.35 68.58 0)
		(effects
			(font
				(size 1.27 1.27)
			)
			(justify left bottom)
		)
	)
	(label "USBC3_RX_{1}-"
		(at 260.35 83.82 0)
		(effects
			(font
				(size 1.27 1.27)
			)
			(justify left bottom)
		)
	)
	(label "USBC3_CC_{1}"
		(at 260.35 60.96 0)
		(effects
			(font
				(size 1.27 1.27)
			)
			(justify left bottom)
		)
	)
	(label "PRT_CTL1"
		(at 302.26 158.75 0)
		(effects
			(font
				(size 1.27 1.27)
			)
			(justify left bottom)
		)
	)
	(label "USBC3_TX_{1}+"
		(at 200.66 114.3 180)
		(effects
			(font
				(size 1.27 1.27)
			)
			(justify right bottom)
		)
	)
	(label "CFG_STRAP2"
		(at 54.61 187.96 180)
		(effects
			(font
				(size 1.27 1.27)
			)
			(justify right bottom)
		)
	)
	(label "USB2.D+"
		(at 74.93 85.09 0)
		(effects
			(font
				(size 1.27 1.27)
			)
			(justify left bottom)
		)
	)
	(label "HUB_SPI_D0"
		(at 196.85 179.07 180)
		(effects
			(font
				(size 1.27 1.27)
			)
			(justify right bottom)
		)
	)
	(label "USBC4_D+"
		(at 200.66 91.44 180)
		(effects
			(font
				(size 1.27 1.27)
			)
			(justify right bottom)
		)
	)
	(label "TEST3"
		(at 120.65 176.53 0)
		(effects
			(font
				(size 1.27 1.27)
			)
			(justify left bottom)
		)
	)
	(label "USBC4_RX_{2}+"
		(at 260.35 218.44 0)
		(effects
			(font
				(size 1.27 1.27)
			)
			(justify left bottom)
		)
	)
	(label "USBC4_CONN_TX1_N"
		(at 312.42 213.36 180)
		(effects
			(font
				(size 1.27 1.27)
			)
			(justify right bottom)
		)
	)
	(label "USBC3_RX_{2}-"
		(at 260.35 99.06 0)
		(effects
			(font
				(size 1.27 1.27)
			)
			(justify left bottom)
		)
	)
	(label "USBC3_TX_{2}+"
		(at 200.66 124.46 180)
		(effects
			(font
				(size 1.27 1.27)
			)
			(justify right bottom)
		)
	)
	(label "USBC4_RX_{1}-"
		(at 260.35 205.74 0)
		(effects
			(font
				(size 1.27 1.27)
			)
			(justify left bottom)
		)
	)
	(label "DP2_VCONN1"
		(at 114.3 114.3 0)
		(effects
			(font
				(size 1.27 1.27)
			)
			(justify left bottom)
		)
	)
	(label "SPI_{HUB_DEBUG}.MISO"
		(at 55.88 271.78 0)
		(effects
			(font
				(size 1.27 1.27)
			)
			(justify left bottom)
		)
	)
	(label "USBC3_CONN_TX2_P"
		(at 312.42 106.68 180)
		(effects
			(font
				(size 1.27 1.27)
			)
			(justify right bottom)
		)
	)
	(label "USBC4_CC_{1}"
		(at 200.66 66.04 180)
		(effects
			(font
				(size 1.27 1.27)
			)
			(justify right bottom)
		)
	)
	(label "USBC4_VBUS_MON"
		(at 200.66 63.5 180)
		(effects
			(font
				(size 1.27 1.27)
			)
			(justify right bottom)
		)
	)
	(label "USBC3_TX_{1}-"
		(at 200.66 116.84 180)
		(effects
			(font
				(size 1.27 1.27)
			)
			(justify right bottom)
		)
	)
	(hierarchical_label "SPI_{HUB_DEBUG}{SPI}"
		(shape input)
		(at 49.53 269.24 180)
		(effects
			(font
				(size 1.27 1.27)
			)
			(justify right)
		)
	)
	(hierarchical_label "USB2{USB}"
		(shape bidirectional)
		(at 68.58 82.55 180)
		(effects
			(font
				(size 1.27 1.27)
			)
			(justify right)
		)
	)
	(hierarchical_label "I2C_{SYS}{I2C}"
		(shape bidirectional)
		(at 96.52 134.62 180)
		(effects
			(font
				(size 1.27 1.27)
			)
			(justify right)
		)
	)
	(hierarchical_label "USBSS2{USBSS}"
		(shape bidirectional)
		(at 68.58 72.39 180)
		(effects
			(font
				(size 1.27 1.27)
			)
			(justify right)
		)
	)
	(rule_area
		(polyline
			(pts
				(xy 313.5312 231.14) (xy 259.2387 231.14) (xy 259.08 200.66) (xy 313.3725 200.66)
			)
			(stroke
				(width 0)
				(type dash)
			)
			(fill
				(type none)
			)
		)
	)
	(rule_area
		(polyline
			(pts
				(xy 123.19 83.185) (xy 73.66 83.185) (xy 73.66 72.39) (xy 123.19 72.39)
			)
			(stroke
				(width 0)
				(type dash)
			)
			(fill
				(type none)
			)
		)
	)
	(rule_area
		(polyline
			(pts
				(xy 313.5312 109.22) (xy 259.2387 109.22) (xy 259.08 78.74) (xy 313.3725 78.74)
			)
			(stroke
				(width 0)
				(type dash)
			)
			(fill
				(type none)
			)
		)
	)
	(rule_area
		(polyline
			(pts
				(xy 271.145 193.675) (xy 259.08 193.675) (xy 259.08 187.96) (xy 271.145 187.96)
			)
			(stroke
				(width 0)
				(type dash)
			)
			(fill
				(type none)
			)
		)
	)
	(rule_area
		(polyline
			(pts
				(xy 123.19 89.535) (xy 73.66 89.535) (xy 73.66 83.185) (xy 123.19 83.185)
			)
			(stroke
				(width 0)
				(type dash)
			)
			(fill
				(type none)
			)
		)
	)
	(rule_area
		(polyline
			(pts
				(xy 271.145 71.755) (xy 259.08 71.755) (xy 259.08 66.04) (xy 271.145 66.04)
			)
			(stroke
				(width 0)
				(type dash)
			)
			(fill
				(type none)
			)
		)
	)
	(netclass_flag ""
		(length 2.54)
		(shape round)
		(at 259.08 200.66 0)
		(effects
			(font
				(size 1.27 1.27)
			)
			(justify left bottom)
		)
		(property "Netclass" "85Ohm-diff_USB_SS"
			(at 260.096 198.12 0)
			(effects
				(font
					(size 1.27 1.27)
				)
				(justify left)
			)
		)
		(property "Component Class" ""
			(at 96.52 158.75 0)
			(effects
				(font
					(size 1.27 1.27)
					(italic yes)
				)
				(justify right)
			)
		)
	)
	(netclass_flag ""
		(length 2.54)
		(shape round)
		(at 73.66 72.39 0)
		(effects
			(font
				(size 1.27 1.27)
			)
			(justify left bottom)
		)
		(property "Netclass" "85Ohm-diff_USB_SS"
			(at 74.676 69.85 0)
			(effects
				(font
					(size 1.27 1.27)
				)
				(justify left)
			)
		)
		(property "Component Class" ""
			(at -88.9 30.48 0)
			(effects
				(font
					(size 1.27 1.27)
					(italic yes)
				)
				(justify right)
			)
		)
	)
	(netclass_flag ""
		(length 2.54)
		(shape round)
		(at 259.08 78.74 0)
		(effects
			(font
				(size 1.27 1.27)
			)
			(justify left bottom)
		)
		(property "Netclass" "85Ohm-diff_USB_SS"
			(at 260.096 76.2 0)
			(effects
				(font
					(size 1.27 1.27)
				)
				(justify left)
			)
		)
		(property "Component Class" ""
			(at 96.52 36.83 0)
			(effects
				(font
					(size 1.27 1.27)
					(italic yes)
				)
				(justify right)
			)
		)
	)
	(netclass_flag ""
		(length 2.54)
		(shape round)
		(at 259.08 66.04 0)
		(effects
			(font
				(size 1.27 1.27)
			)
			(justify left bottom)
		)
		(property "Netclass" "90Ohm-diff_USB_2.0"
			(at 257.556 65.278 0)
			(effects
				(font
					(size 1.27 1.27)
				)
				(justify right)
			)
		)
		(property "Component Class" ""
			(at 96.52 24.13 0)
			(effects
				(font
					(size 1.27 1.27)
					(italic yes)
				)
				(justify right)
			)
		)
	)
	(netclass_flag ""
		(length 2.54)
		(shape round)
		(at 259.08 187.96 0)
		(effects
			(font
				(size 1.27 1.27)
			)
			(justify left bottom)
		)
		(property "Netclass" "90Ohm-diff_USB_2.0"
			(at 279.908 186.69 0)
			(effects
				(font
					(size 1.27 1.27)
				)
				(justify right)
			)
		)
		(property "Component Class" ""
			(at 96.52 146.05 0)
			(effects
				(font
					(size 1.27 1.27)
					(italic yes)
				)
				(justify right)
			)
		)
	)
	(netclass_flag ""
		(length 2.54)
		(shape round)
		(at 73.66 88.9 90)
		(effects
			(font
				(size 1.27 1.27)
			)
			(justify left bottom)
		)
		(property "Netclass" "90Ohm-diff_USB_2.0"
			(at 50.038 88.9 0)
			(effects
				(font
					(size 1.27 1.27)
				)
				(justify left)
			)
		)
		(property "Component Class" ""
			(at 31.75 251.46 90)
			(effects
				(font
					(size 1.27 1.27)
					(italic yes)
				)
				(justify right)
			)
		)
	)
	(symbol
		(lib_id "antmicroCapacitors0402:C_100n_0402")
		(at 71.12 153.67 90)
		(unit 1)
		(exclude_from_sim no)
		(in_bom yes)
		(on_board yes)
		(dnp no)
		(fields_autoplaced yes)
		(property "Reference" "C93"
			(at 73.66 149.8536 90)
			(effects
				(font
					(size 1.27 1.27)
					(thickness 0.15)
				)
				(justify right)
			)
		)
		(property "Value" "C_100n_0402"
			(at 93.98 138.43 0)
			(effects
				(font
					(size 1.27 1.27)
					(thickness 0.15)
				)
				(justify left bottom)
				(hide yes)
			)
		)
		(property "Footprint" "antmicro-footprints:C_0402_1005Metric"
			(at 96.52 138.43 0)
			(effects
				(font
					(size 1.27 1.27)
					(thickness 0.15)
				)
				(justify left bottom)
				(hide yes)
			)
		)
		(property "Datasheet" "https://www.murata.com/products/productdetail?partno=GRM155R61H104KE14%23"
			(at 99.06 138.43 0)
			(effects
				(font
					(size 1.27 1.27)
					(thickness 0.15)
				)
				(justify left bottom)
				(hide yes)
			)
		)
		(property "Description" "SMD Multilayer Ceramic Capacitor, 0.1 µF, 50 V, 0402 [1005 Metric], ± 10%, X5R, GRM Series"
			(at 71.12 153.67 0)
			(effects
				(font
					(size 1.27 1.27)
				)
				(hide yes)
			)
		)
		(property "MPN" "GRM155R61H104KE14D"
			(at 101.6 138.43 0)
			(effects
				(font
					(size 1.27 1.27)
					(thickness 0.15)
				)
				(justify left bottom)
				(hide yes)
			)
		)
		(property "Val" "100n"
			(at 73.66 152.3936 90)
			(effects
				(font
					(size 1.27 1.27)
					(thickness 0.15)
				)
				(justify right)
			)
		)
		(property "Voltage" "50V"
			(at 81.28 138.43 0)
			(effects
				(font
					(size 1.27 1.27)
					(thickness 0.15)
				)
				(justify left bottom)
				(hide yes)
			)
		)
		(property "Dielectric" "X5R"
			(at 83.82 138.43 0)
			(effects
				(font
					(size 1.27 1.27)
					(thickness 0.15)
				)
				(justify left bottom)
				(hide yes)
			)
		)
		(property "Manufacturer" "Murata"
			(at 86.36 138.43 0)
			(effects
				(font
					(size 1.27 1.27)
					(thickness 0.15)
				)
				(justify left bottom)
				(hide yes)
			)
		)
		(property "License" "Apache-2.0"
			(at 88.9 138.43 0)
			(effects
				(font
					(size 1.27 1.27)
					(thickness 0.15)
				)
				(justify left bottom)
				(hide yes)
			)
		)
		(property "Author" "Antmicro"
			(at 91.44 138.43 0)
			(effects
				(font
					(size 1.27 1.27)
					(thickness 0.15)
				)
				(justify left bottom)
				(hide yes)
			)
		)
		(pin "2"
		)
		(pin "1"
		)
		(instances
			(project "jetson-agx-thor-baseboard"
				(path ""
					(reference "C93")
					(unit 1)
				)
			)
		)
	)
	(symbol
		(lib_id "antmicroResistors0402:R_2R2_0402")
		(at 234.95 255.27 0)
		(unit 1)
		(exclude_from_sim no)
		(in_bom yes)
		(on_board yes)
		(dnp no)
		(property "Reference" "R337"
			(at 237.236 252.984 0)
			(effects
				(font
					(size 1.27 1.27)
					(thickness 0.15)
				)
			)
		)
		(property "Value" "R_2R2_0402"
			(at 255.27 267.97 0)
			(effects
				(font
					(size 1.27 1.27)
					(thickness 0.15)
				)
				(justify left bottom)
				(hide yes)
			)
		)
		(property "Footprint" "antmicro-footprints:R_0402_1005Metric"
			(at 255.27 270.51 0)
			(effects
				(font
					(size 1.27 1.27)
					(thickness 0.15)
				)
				(justify left bottom)
				(hide yes)
			)
		)
		(property "Datasheet" "https://www.bourns.com/docs/product-datasheets/cr.pdf"
			(at 255.27 273.05 0)
			(effects
				(font
					(size 1.27 1.27)
					(thickness 0.15)
				)
				(justify left bottom)
				(hide yes)
			)
		)
		(property "Description" "SMD Chip Resistor, 2.2 ohm, ± 1%, 62.5 mW, 0402 [1005 Metric], Thick Film, General Purpose"
			(at 255.27 285.75 0)
			(effects
				(font
					(size 1.27 1.27)
				)
				(justify left bottom)
				(hide yes)
			)
		)
		(property "MPN" "CR0402-FX-2R20GLF"
			(at 255.27 275.59 0)
			(effects
				(font
					(size 1.27 1.27)
					(thickness 0.15)
				)
				(justify left bottom)
				(hide yes)
			)
		)
		(property "Manufacturer" "Bourns"
			(at 255.27 278.13 0)
			(effects
				(font
					(size 1.27 1.27)
					(thickness 0.15)
				)
				(justify left bottom)
				(hide yes)
			)
		)
		(property "License" "Apache-2.0"
			(at 255.27 280.67 0)
			(effects
				(font
					(size 1.27 1.27)
					(thickness 0.15)
				)
				(justify left bottom)
				(hide yes)
			)
		)
		(property "Author" "Antmicro"
			(at 255.27 283.21 0)
			(effects
				(font
					(size 1.27 1.27)
					(thickness 0.15)
				)
				(justify left bottom)
				(hide yes)
			)
		)
		(property "Val" "2R2"
			(at 237.236 257.556 0)
			(effects
				(font
					(size 1.27 1.27)
					(thickness 0.15)
				)
			)
		)
		(property "Tolerance" "1%"
			(at 255.27 265.43 0)
			(effects
				(font
					(size 1.27 1.27)
				)
				(justify left bottom)
				(hide yes)
			)
		)
		(pin "2"
		)
		(pin "1"
		)
		(instances
			(project "jetson-agx-thor-baseboard"
				(path ""
					(reference "R337")
					(unit 1)
				)
			)
		)
	)
	(symbol
		(lib_id "antmicropower:+5V")
		(at 207.01 229.87 0)
		(unit 1)
		(exclude_from_sim no)
		(in_bom yes)
		(on_board yes)
		(dnp no)
		(property "Reference" "#PWR0679"
			(at 207.01 233.68 0)
			(effects
				(font
					(size 1.27 1.27)
				)
				(justify left bottom)
				(hide yes)
			)
		)
		(property "Value" "+5V"
			(at 205.105 226.695 0)
			(effects
				(font
					(size 1.27 1.27)
					(thickness 0.15)
				)
				(justify left bottom)
			)
		)
		(property "Footprint" ""
			(at 222.25 237.49 0)
			(effects
				(font
					(size 1.27 1.27)
					(thickness 0.15)
				)
				(justify left bottom)
				(hide yes)
			)
		)
		(property "Datasheet" ""
			(at 222.25 240.03 0)
			(effects
				(font
					(size 1.27 1.27)
					(thickness 0.15)
				)
				(justify left bottom)
				(hide yes)
			)
		)
		(property "Description" ""
			(at 207.01 229.87 0)
			(effects
				(font
					(size 1.27 1.27)
				)
				(hide yes)
			)
		)
		(property "Author" "Antmicro"
			(at 222.25 237.49 0)
			(effects
				(font
					(size 1.27 1.27)
					(thickness 0.15)
				)
				(justify left bottom)
				(hide yes)
			)
		)
		(property "License" "Apache-2.0"
			(at 222.25 240.03 0)
			(effects
				(font
					(size 1.27 1.27)
					(thickness 0.15)
				)
				(justify left bottom)
				(hide yes)
			)
		)
		(pin "1"
		)
		(instances
			(project "jetson-agx-thor-baseboard"
				(path ""
					(reference "#PWR0679")
					(unit 1)
				)
			)
		)
	)
	(symbol
		(lib_id "antmicroTestPoints:TP_0.75mm_SMD")
		(at 114.3 96.52 180)
		(unit 1)
		(exclude_from_sim no)
		(in_bom no)
		(on_board yes)
		(dnp no)
		(property "Reference" "TP68"
			(at 110.236 95.758 0)
			(effects
				(font
					(size 1.27 1.27)
				)
				(justify left bottom)
			)
		)
		(property "Value" "TP_0.75mm_SMD"
			(at 104.14 92.71 0)
			(effects
				(font
					(size 1.27 1.27)
					(thickness 0.15)
				)
				(justify left bottom)
				(hide yes)
			)
		)
		(property "Footprint" "antmicro-footprints:TP_SMD_0.75mm"
			(at 104.14 90.17 0)
			(effects
				(font
					(size 1.27 1.27)
					(thickness 0.15)
				)
				(justify left bottom)
				(hide yes)
			)
		)
		(property "Datasheet" ""
			(at 96.52 83.82 0)
			(effects
				(font
					(size 1.27 1.27)
					(thickness 0.15)
				)
				(justify left bottom)
				(hide yes)
			)
		)
		(property "Description" "SMT test point"
			(at 114.3 96.52 0)
			(effects
				(font
					(size 1.27 1.27)
				)
				(hide yes)
			)
		)
		(property "MPN" ""
			(at 103.505 85.09 0)
			(effects
				(font
					(size 1.27 1.27)
					(thickness 0.15)
				)
				(justify left bottom)
				(hide yes)
			)
		)
		(property "Manufacturer" ""
			(at 103.505 90.17 0)
			(effects
				(font
					(size 1.27 1.27)
					(thickness 0.15)
				)
				(justify left bottom)
				(hide yes)
			)
		)
		(property "Author" "Antmicro"
			(at 104.14 87.63 0)
			(effects
				(font
					(size 1.27 1.27)
					(thickness 0.15)
				)
				(justify left bottom)
				(hide yes)
			)
		)
		(property "License" "Apache-2.0"
			(at 104.14 85.09 0)
			(effects
				(font
					(size 1.27 1.27)
					(thickness 0.15)
				)
				(justify left bottom)
				(hide yes)
			)
		)
		(pin "1"
		)
		(instances
			(project "jetson-agx-thor-baseboard"
				(path ""
					(reference "TP68")
					(unit 1)
				)
			)
		)
	)
	(symbol
		(lib_id "antmicroResistors0402:R_10k_0402")
		(at 27.94 184.15 90)
		(unit 1)
		(exclude_from_sim no)
		(in_bom yes)
		(on_board yes)
		(dnp no)
		(property "Reference" "R87"
			(at 29.21 180.34 90)
			(effects
				(font
					(size 1.27 1.27)
				)
				(justify right)
			)
		)
		(property "Value" "R_10k_0402"
			(at 40.64 163.83 0)
			(effects
				(font
					(size 1.27 1.27)
					(thickness 0.15)
				)
				(justify left bottom)
				(hide yes)
			)
		)
		(property "Footprint" "antmicro-footprints:R_0402_1005Metric"
			(at 43.18 163.83 0)
			(effects
				(font
					(size 1.27 1.27)
					(thickness 0.15)
				)
				(justify left bottom)
				(hide yes)
			)
		)
		(property "Datasheet" "https://www.bourns.com/docs/product-datasheets/cr.pdf"
			(at 45.72 163.83 0)
			(effects
				(font
					(size 1.27 1.27)
					(thickness 0.15)
				)
				(justify left bottom)
				(hide yes)
			)
		)
		(property "Description" "SMD Chip Resistor, 10 kohm, ± 1%, 62.5 mW, 0402 [1005 Metric], Thick Film, General Purpose"
			(at 27.94 184.15 0)
			(effects
				(font
					(size 1.27 1.27)
				)
				(hide yes)
			)
		)
		(property "Manufacturer" "Bourns"
			(at 50.8 163.83 0)
			(effects
				(font
					(size 1.27 1.27)
					(thickness 0.15)
				)
				(justify left bottom)
				(hide yes)
			)
		)
		(property "MPN" "CR0402-FX-1002GLF"
			(at 48.26 163.83 0)
			(effects
				(font
					(size 1.27 1.27)
					(thickness 0.15)
				)
				(justify left bottom)
				(hide yes)
			)
		)
		(property "Val" "10k"
			(at 29.21 182.88 90)
			(effects
				(font
					(size 1.27 1.27)
					(thickness 0.15)
				)
				(justify right)
			)
		)
		(property "License" "Apache-2.0"
			(at 53.34 163.83 0)
			(effects
				(font
					(size 1.27 1.27)
					(thickness 0.15)
				)
				(justify left bottom)
				(hide yes)
			)
		)
		(property "Author" "Antmicro"
			(at 55.88 163.83 0)
			(effects
				(font
					(size 1.27 1.27)
					(thickness 0.15)
				)
				(justify left bottom)
				(hide yes)
			)
		)
		(property "Tolerance" "1%"
			(at 38.1 163.83 0)
			(effects
				(font
					(size 1.27 1.27)
				)
				(justify left bottom)
				(hide yes)
			)
		)
		(pin "1"
		)
		(pin "2"
		)
		(instances
			(project "jetson-agx-thor-baseboard"
				(path ""
					(reference "R87")
					(unit 1)
				)
			)
		)
	)
	(symbol
		(lib_id "antmicroCapacitors0402:C_100n_0402")
		(at 88.9 48.26 90)
		(unit 1)
		(exclude_from_sim no)
		(in_bom yes)
		(on_board yes)
		(dnp no)
		(fields_autoplaced yes)
		(property "Reference" "C97"
			(at 91.44 44.4436 90)
			(effects
				(font
					(size 1.27 1.27)
					(thickness 0.15)
				)
				(justify right)
			)
		)
		(property "Value" "C_100n_0402"
			(at 111.76 33.02 0)
			(effects
				(font
					(size 1.27 1.27)
					(thickness 0.15)
				)
				(justify left bottom)
				(hide yes)
			)
		)
		(property "Footprint" "antmicro-footprints:C_0402_1005Metric"
			(at 114.3 33.02 0)
			(effects
				(font
					(size 1.27 1.27)
					(thickness 0.15)
				)
				(justify left bottom)
				(hide yes)
			)
		)
		(property "Datasheet" "https://www.murata.com/products/productdetail?partno=GRM155R61H104KE14%23"
			(at 116.84 33.02 0)
			(effects
				(font
					(size 1.27 1.27)
					(thickness 0.15)
				)
				(justify left bottom)
				(hide yes)
			)
		)
		(property "Description" "SMD Multilayer Ceramic Capacitor, 0.1 µF, 50 V, 0402 [1005 Metric], ± 10%, X5R, GRM Series"
			(at 88.9 48.26 0)
			(effects
				(font
					(size 1.27 1.27)
				)
				(hide yes)
			)
		)
		(property "MPN" "GRM155R61H104KE14D"
			(at 119.38 33.02 0)
			(effects
				(font
					(size 1.27 1.27)
					(thickness 0.15)
				)
				(justify left bottom)
				(hide yes)
			)
		)
		(property "Val" "100n"
			(at 91.44 46.9836 90)
			(effects
				(font
					(size 1.27 1.27)
					(thickness 0.15)
				)
				(justify right)
			)
		)
		(property "Voltage" "50V"
			(at 99.06 33.02 0)
			(effects
				(font
					(size 1.27 1.27)
					(thickness 0.15)
				)
				(justify left bottom)
				(hide yes)
			)
		)
		(property "Dielectric" "X5R"
			(at 101.6 33.02 0)
			(effects
				(font
					(size 1.27 1.27)
					(thickness 0.15)
				)
				(justify left bottom)
				(hide yes)
			)
		)
		(property "Manufacturer" "Murata"
			(at 104.14 33.02 0)
			(effects
				(font
					(size 1.27 1.27)
					(thickness 0.15)
				)
				(justify left bottom)
				(hide yes)
			)
		)
		(property "License" "Apache-2.0"
			(at 106.68 33.02 0)
			(effects
				(font
					(size 1.27 1.27)
					(thickness 0.15)
				)
				(justify left bottom)
				(hide yes)
			)
		)
		(property "Author" "Antmicro"
			(at 109.22 33.02 0)
			(effects
				(font
					(size 1.27 1.27)
					(thickness 0.15)
				)
				(justify left bottom)
				(hide yes)
			)
		)
		(pin "1"
		)
		(pin "2"
		)
		(instances
			(project "jetson-agx-thor-baseboard"
				(path ""
					(reference "C97")
					(unit 1)
				)
			)
		)
	)
	(symbol
		(lib_id "antmicropower:GND")
		(at 360.68 161.29 0)
		(unit 1)
		(exclude_from_sim no)
		(in_bom yes)
		(on_board yes)
		(dnp no)
		(property "Reference" "#PWR0466"
			(at 360.68 167.64 0)
			(effects
				(font
					(size 1.27 1.27)
				)
				(justify left bottom)
				(hide yes)
			)
		)
		(property "Value" "GND"
			(at 360.68 165.1 0)
			(effects
				(font
					(size 1.27 1.27)
					(thickness 0.15)
				)
			)
		)
		(property "Footprint" ""
			(at 369.57 168.91 0)
			(effects
				(font
					(size 1.27 1.27)
					(thickness 0.15)
				)
				(justify left bottom)
				(hide yes)
			)
		)
		(property "Datasheet" ""
			(at 369.57 173.99 0)
			(effects
				(font
					(size 1.27 1.27)
					(thickness 0.15)
				)
				(justify left bottom)
				(hide yes)
			)
		)
		(property "Description" ""
			(at 360.68 161.29 0)
			(effects
				(font
					(size 1.27 1.27)
				)
				(hide yes)
			)
		)
		(property "Author" "Antmicro"
			(at 369.57 168.91 0)
			(effects
				(font
					(size 1.27 1.27)
					(thickness 0.15)
				)
				(justify left bottom)
				(hide yes)
			)
		)
		(property "License" "Apache-2.0"
			(at 369.57 171.45 0)
			(effects
				(font
					(size 1.27 1.27)
					(thickness 0.15)
				)
				(justify left bottom)
				(hide yes)
			)
		)
		(pin "1"
		)
		(instances
			(project "jetson-agx-thor-baseboard"
				(path ""
					(reference "#PWR0466")
					(unit 1)
				)
			)
		)
	)
	(symbol
		(lib_id "antmicroTVSDiodes:PESD5Z5_0F")
		(at 374.65 33.02 270)
		(unit 1)
		(exclude_from_sim no)
		(in_bom yes)
		(on_board yes)
		(dnp no)
		(property "Reference" "D45"
			(at 375.92 34.29 90)
			(effects
				(font
					(size 1.27 1.27)
				)
				(justify left)
			)
		)
		(property "Value" "PESD5Z5.0F"
			(at 359.41 54.61 0)
			(effects
				(font
					(size 1.27 1.27)
					(thickness 0.15)
				)
				(justify left bottom)
				(hide yes)
			)
		)
		(property "Footprint" "antmicro-footprints:SOD-523"
			(at 369.57 48.26 0)
			(effects
				(font
					(size 1.27 1.27)
					(thickness 0.15)
				)
				(justify left bottom)
				(hide yes)
			)
		)
		(property "Datasheet" "https://assets.nexperia.com/documents/data-sheet/PESD5Z5_0.pdf"
			(at 367.03 48.26 0)
			(effects
				(font
					(size 1.27 1.27)
					(thickness 0.15)
				)
				(justify left bottom)
				(hide yes)
			)
		)
		(property "Description" "Unidirectional TVS, 30 kV,  SOD-523, 5 V, 89 pF"
			(at 354.33 48.26 0)
			(effects
				(font
					(size 1.27 1.27)
				)
				(justify left bottom)
				(hide yes)
			)
		)
		(property "Manufacturer" "Nexperia"
			(at 364.49 48.26 0)
			(effects
				(font
					(size 1.27 1.27)
					(thickness 0.15)
				)
				(justify left bottom)
				(hide yes)
			)
		)
		(property "MPN" "PESD5Z5.0F"
			(at 375.92 37.084 90)
			(effects
				(font
					(size 1.27 1.27)
					(thickness 0.15)
				)
				(justify left bottom)
			)
		)
		(property "Author" "Antmicro"
			(at 359.41 48.26 0)
			(effects
				(font
					(size 1.27 1.27)
					(thickness 0.15)
				)
				(justify left bottom)
				(hide yes)
			)
		)
		(property "License" "Apache-2.0"
			(at 356.87 48.26 0)
			(effects
				(font
					(size 1.27 1.27)
					(thickness 0.15)
				)
				(justify left bottom)
				(hide yes)
			)
		)
		(pin "1"
		)
		(pin "2"
		)
		(instances
			(project "jetson-agx-thor-baseboard"
				(path ""
					(reference "D45")
					(unit 1)
				)
			)
		)
	)
	(symbol
		(lib_id "antmicroPMICPowerDistributionSwitchesLoadDrivers:AP22615A_TSOT26")
		(at 318.77 31.75 0)
		(unit 1)
		(exclude_from_sim no)
		(in_bom yes)
		(on_board yes)
		(dnp no)
		(property "Reference" "U18"
			(at 326.39 25.4 0)
			(effects
				(font
					(size 1.27 1.27)
				)
			)
		)
		(property "Value" "AP22615A_TSOT26"
			(at 349.25 36.83 0)
			(effects
				(font
					(size 1.27 1.27)
					(thickness 0.15)
				)
				(justify left bottom)
				(hide yes)
			)
		)
		(property "Footprint" "antmicro-footprints:TSOT23-6"
			(at 349.25 39.37 0)
			(effects
				(font
					(size 1.27 1.27)
					(thickness 0.15)
				)
				(justify left bottom)
				(hide yes)
			)
		)
		(property "Datasheet" "https://www.mouser.com/datasheet/2/115/DIOD_S_A0008958405_1-2543193.pdf"
			(at 349.25 41.91 0)
			(effects
				(font
					(size 1.27 1.27)
					(thickness 0.15)
				)
				(justify left bottom)
				(hide yes)
			)
		)
		(property "Description" "Power Load Distribution Switch, High Side, Active High, 1 Output, 5.5 V, 3.6 A, 0.04 ohm, TSOT-26-6"
			(at 318.77 31.75 0)
			(effects
				(font
					(size 1.27 1.27)
				)
				(hide yes)
			)
		)
		(property "MPN" "AP22615AWU-7"
			(at 326.39 27.94 0)
			(effects
				(font
					(size 1.27 1.27)
					(thickness 0.15)
				)
			)
		)
		(property "Manufacturer" "Diodes Incorporated"
			(at 349.25 46.99 0)
			(effects
				(font
					(size 1.27 1.27)
					(thickness 0.15)
				)
				(justify left bottom)
				(hide yes)
			)
		)
		(property "Author" "Antmicro"
			(at 349.25 49.53 0)
			(effects
				(font
					(size 1.27 1.27)
					(thickness 0.15)
				)
				(justify left bottom)
				(hide yes)
			)
		)
		(property "License" "Apache-2.0"
			(at 349.25 52.07 0)
			(effects
				(font
					(size 1.27 1.27)
					(thickness 0.15)
				)
				(justify left bottom)
				(hide yes)
			)
		)
		(pin "1"
		)
		(pin "2"
		)
		(pin "3"
		)
		(pin "4"
		)
		(pin "5"
		)
		(pin "6"
		)
		(instances
			(project "jetson-agx-thor-baseboard"
				(path ""
					(reference "U18")
					(unit 1)
				)
			)
		)
	)
	(symbol
		(lib_id "antmicropower:+5V")
		(at 148.59 229.87 0)
		(unit 1)
		(exclude_from_sim no)
		(in_bom yes)
		(on_board yes)
		(dnp no)
		(property "Reference" "#PWR0235"
			(at 148.59 233.68 0)
			(effects
				(font
					(size 1.27 1.27)
				)
				(justify left bottom)
				(hide yes)
			)
		)
		(property "Value" "+5V"
			(at 146.685 226.695 0)
			(effects
				(font
					(size 1.27 1.27)
					(thickness 0.15)
				)
				(justify left bottom)
			)
		)
		(property "Footprint" ""
			(at 163.83 237.49 0)
			(effects
				(font
					(size 1.27 1.27)
					(thickness 0.15)
				)
				(justify left bottom)
				(hide yes)
			)
		)
		(property "Datasheet" ""
			(at 163.83 240.03 0)
			(effects
				(font
					(size 1.27 1.27)
					(thickness 0.15)
				)
				(justify left bottom)
				(hide yes)
			)
		)
		(property "Description" ""
			(at 148.59 229.87 0)
			(effects
				(font
					(size 1.27 1.27)
				)
				(hide yes)
			)
		)
		(property "Author" "Antmicro"
			(at 163.83 237.49 0)
			(effects
				(font
					(size 1.27 1.27)
					(thickness 0.15)
				)
				(justify left bottom)
				(hide yes)
			)
		)
		(property "License" "Apache-2.0"
			(at 163.83 240.03 0)
			(effects
				(font
					(size 1.27 1.27)
					(thickness 0.15)
				)
				(justify left bottom)
				(hide yes)
			)
		)
		(pin "1"
		)
		(instances
			(project "jetson-agx-thor-baseboard"
				(path ""
					(reference "#PWR0235")
					(unit 1)
				)
			)
		)
	)
	(symbol
		(lib_id "antmicropower:GND")
		(at 71.12 153.67 0)
		(mirror y)
		(unit 1)
		(exclude_from_sim no)
		(in_bom yes)
		(on_board yes)
		(dnp no)
		(property "Reference" "#PWR0188"
			(at 71.12 160.02 0)
			(effects
				(font
					(size 1.27 1.27)
				)
				(justify left bottom)
				(hide yes)
			)
		)
		(property "Value" "GND"
			(at 71.12 157.48 0)
			(effects
				(font
					(size 1.27 1.27)
					(thickness 0.15)
				)
			)
		)
		(property "Footprint" ""
			(at 62.23 161.29 0)
			(effects
				(font
					(size 1.27 1.27)
					(thickness 0.15)
				)
				(justify left bottom)
				(hide yes)
			)
		)
		(property "Datasheet" ""
			(at 62.23 166.37 0)
			(effects
				(font
					(size 1.27 1.27)
					(thickness 0.15)
				)
				(justify left bottom)
				(hide yes)
			)
		)
		(property "Description" ""
			(at 71.12 153.67 0)
			(effects
				(font
					(size 1.27 1.27)
				)
				(hide yes)
			)
		)
		(property "Author" "Antmicro"
			(at 62.23 161.29 0)
			(effects
				(font
					(size 1.27 1.27)
					(thickness 0.15)
				)
				(justify left bottom)
				(hide yes)
			)
		)
		(property "License" "Apache-2.0"
			(at 62.23 163.83 0)
			(effects
				(font
					(size 1.27 1.27)
					(thickness 0.15)
				)
				(justify left bottom)
				(hide yes)
			)
		)
		(pin "1"
		)
		(instances
			(project "jetson-agx-thor-baseboard"
				(path ""
					(reference "#PWR0188")
					(unit 1)
				)
			)
		)
	)
	(symbol
		(lib_id "antmicropower:GND")
		(at 327.66 114.3 0)
		(unit 1)
		(exclude_from_sim no)
		(in_bom yes)
		(on_board yes)
		(dnp no)
		(property "Reference" "#PWR0208"
			(at 327.66 120.65 0)
			(effects
				(font
					(size 1.27 1.27)
				)
				(justify left bottom)
				(hide yes)
			)
		)
		(property "Value" "GND"
			(at 327.66 118.11 0)
			(effects
				(font
					(size 1.27 1.27)
					(thickness 0.15)
				)
			)
		)
		(property "Footprint" ""
			(at 336.55 121.92 0)
			(effects
				(font
					(size 1.27 1.27)
					(thickness 0.15)
				)
				(justify left bottom)
				(hide yes)
			)
		)
		(property "Datasheet" ""
			(at 336.55 127 0)
			(effects
				(font
					(size 1.27 1.27)
					(thickness 0.15)
				)
				(justify left bottom)
				(hide yes)
			)
		)
		(property "Description" ""
			(at 327.66 114.3 0)
			(effects
				(font
					(size 1.27 1.27)
				)
				(hide yes)
			)
		)
		(property "Author" "Antmicro"
			(at 336.55 121.92 0)
			(effects
				(font
					(size 1.27 1.27)
					(thickness 0.15)
				)
				(justify left bottom)
				(hide yes)
			)
		)
		(property "License" "Apache-2.0"
			(at 336.55 124.46 0)
			(effects
				(font
					(size 1.27 1.27)
					(thickness 0.15)
				)
				(justify left bottom)
				(hide yes)
			)
		)
		(pin "1"
		)
		(instances
			(project "jetson-agx-thor-baseboard"
				(path ""
					(reference "#PWR0208")
					(unit 1)
				)
			)
		)
	)
	(symbol
		(lib_id "antmicropower:+5V")
		(at 207.01 254 0)
		(unit 1)
		(exclude_from_sim no)
		(in_bom yes)
		(on_board yes)
		(dnp no)
		(property "Reference" "#PWR0690"
			(at 207.01 257.81 0)
			(effects
				(font
					(size 1.27 1.27)
				)
				(justify left bottom)
				(hide yes)
			)
		)
		(property "Value" "+5V"
			(at 205.105 250.825 0)
			(effects
				(font
					(size 1.27 1.27)
					(thickness 0.15)
				)
				(justify left bottom)
			)
		)
		(property "Footprint" ""
			(at 222.25 261.62 0)
			(effects
				(font
					(size 1.27 1.27)
					(thickness 0.15)
				)
				(justify left bottom)
				(hide yes)
			)
		)
		(property "Datasheet" ""
			(at 222.25 264.16 0)
			(effects
				(font
					(size 1.27 1.27)
					(thickness 0.15)
				)
				(justify left bottom)
				(hide yes)
			)
		)
		(property "Description" ""
			(at 207.01 254 0)
			(effects
				(font
					(size 1.27 1.27)
				)
				(hide yes)
			)
		)
		(property "Author" "Antmicro"
			(at 222.25 261.62 0)
			(effects
				(font
					(size 1.27 1.27)
					(thickness 0.15)
				)
				(justify left bottom)
				(hide yes)
			)
		)
		(property "License" "Apache-2.0"
			(at 222.25 264.16 0)
			(effects
				(font
					(size 1.27 1.27)
					(thickness 0.15)
				)
				(justify left bottom)
				(hide yes)
			)
		)
		(pin "1"
		)
		(instances
			(project "jetson-agx-thor-baseboard"
				(path ""
					(reference "#PWR0690")
					(unit 1)
				)
			)
		)
	)
	(symbol
		(lib_id "antmicropower:GND")
		(at 205.74 196.85 0)
		(unit 1)
		(exclude_from_sim no)
		(in_bom yes)
		(on_board yes)
		(dnp no)
		(property "Reference" "#PWR0412"
			(at 205.74 203.2 0)
			(effects
				(font
					(size 1.27 1.27)
				)
				(justify left bottom)
				(hide yes)
			)
		)
		(property "Value" "GND"
			(at 205.74 200.66 0)
			(effects
				(font
					(size 1.27 1.27)
					(thickness 0.15)
				)
			)
		)
		(property "Footprint" ""
			(at 214.63 204.47 0)
			(effects
				(font
					(size 1.27 1.27)
					(thickness 0.15)
				)
				(justify left bottom)
				(hide yes)
			)
		)
		(property "Datasheet" ""
			(at 214.63 209.55 0)
			(effects
				(font
					(size 1.27 1.27)
					(thickness 0.15)
				)
				(justify left bottom)
				(hide yes)
			)
		)
		(property "Description" ""
			(at 205.74 196.85 0)
			(effects
				(font
					(size 1.27 1.27)
				)
				(hide yes)
			)
		)
		(property "Author" "Antmicro"
			(at 214.63 204.47 0)
			(effects
				(font
					(size 1.27 1.27)
					(thickness 0.15)
				)
				(justify left bottom)
				(hide yes)
			)
		)
		(property "License" "Apache-2.0"
			(at 214.63 207.01 0)
			(effects
				(font
					(size 1.27 1.27)
					(thickness 0.15)
				)
				(justify left bottom)
				(hide yes)
			)
		)
		(pin "1"
		)
		(instances
			(project "jetson-agx-thor-baseboard"
				(path ""
					(reference "#PWR0412")
					(unit 1)
				)
			)
		)
	)
	(symbol
		(lib_id "antmicroResistors0402:R_200k_0402")
		(at 43.18 196.85 90)
		(unit 1)
		(exclude_from_sim no)
		(in_bom yes)
		(on_board yes)
		(dnp no)
		(property "Reference" "R91"
			(at 44.196 193.04 90)
			(effects
				(font
					(size 1.27 1.27)
					(thickness 0.15)
				)
				(justify right)
			)
		)
		(property "Value" "R_200k_0402"
			(at 55.88 176.53 0)
			(effects
				(font
					(size 1.27 1.27)
					(thickness 0.15)
				)
				(justify left bottom)
				(hide yes)
			)
		)
		(property "Footprint" "antmicro-footprints:R_0402_1005Metric"
			(at 58.42 176.53 0)
			(effects
				(font
					(size 1.27 1.27)
					(thickness 0.15)
				)
				(justify left bottom)
				(hide yes)
			)
		)
		(property "Datasheet" "https://www.bourns.com/docs/product-datasheets/cr.pdf"
			(at 60.96 176.53 0)
			(effects
				(font
					(size 1.27 1.27)
					(thickness 0.15)
				)
				(justify left bottom)
				(hide yes)
			)
		)
		(property "Description" "SMD Chip Resistor, 200 kohm, ± 1%, 62.5 mW, 0402 [1005 Metric], Thick Film, General Purpose"
			(at 43.18 196.85 0)
			(effects
				(font
					(size 1.27 1.27)
				)
				(hide yes)
			)
		)
		(property "MPN" "CR0402-FX-2003GLF"
			(at 63.5 176.53 0)
			(effects
				(font
					(size 1.27 1.27)
					(thickness 0.15)
				)
				(justify left bottom)
				(hide yes)
			)
		)
		(property "Manufacturer" "Bourns"
			(at 66.04 176.53 0)
			(effects
				(font
					(size 1.27 1.27)
					(thickness 0.15)
				)
				(justify left bottom)
				(hide yes)
			)
		)
		(property "License" "Apache-2.0"
			(at 68.58 176.53 0)
			(effects
				(font
					(size 1.27 1.27)
					(thickness 0.15)
				)
				(justify left bottom)
				(hide yes)
			)
		)
		(property "Author" "Antmicro"
			(at 71.12 176.53 0)
			(effects
				(font
					(size 1.27 1.27)
					(thickness 0.15)
				)
				(justify left bottom)
				(hide yes)
			)
		)
		(property "Val" "200k"
			(at 44.196 195.58 90)
			(effects
				(font
					(size 1.27 1.27)
					(thickness 0.15)
				)
				(justify right)
			)
		)
		(property "Tolerance" "1%"
			(at 53.34 176.53 0)
			(effects
				(font
					(size 1.27 1.27)
				)
				(justify left bottom)
				(hide yes)
			)
		)
		(pin "1"
		)
		(pin "2"
		)
		(instances
			(project "jetson-agx-thor-baseboard"
				(path ""
					(reference "R91")
					(unit 1)
				)
			)
		)
	)
	(symbol
		(lib_id "antmicroCapacitors0402:C_1n_0402")
		(at 27.94 101.6 90)
		(unit 1)
		(exclude_from_sim no)
		(in_bom yes)
		(on_board yes)
		(dnp no)
		(fields_autoplaced yes)
		(property "Reference" "C195"
			(at 30.48 97.7836 90)
			(effects
				(font
					(size 1.27 1.27)
					(thickness 0.15)
				)
				(justify right)
			)
		)
		(property "Value" "C_1n_0402"
			(at 38.1 81.28 0)
			(effects
				(font
					(size 1.27 1.27)
					(thickness 0.15)
				)
				(justify left bottom)
				(hide yes)
			)
		)
		(property "Footprint" "antmicro-footprints:C_0402_1005Metric"
			(at 40.64 81.28 0)
			(effects
				(font
					(size 1.27 1.27)
					(thickness 0.15)
				)
				(justify left bottom)
				(hide yes)
			)
		)
		(property "Datasheet" "https://www.murata.com/products/productdetail?partno=GRM1555C1H102JA01%23"
			(at 43.18 81.28 0)
			(effects
				(font
					(size 1.27 1.27)
					(thickness 0.15)
				)
				(justify left bottom)
				(hide yes)
			)
		)
		(property "Description" "SMD Multilayer Ceramic Capacitor, 1000 pF, 50 V, 0402 [1005 Metric], ± 5%, C0G / NP0, GRM Series"
			(at 60.96 81.28 0)
			(effects
				(font
					(size 1.27 1.27)
				)
				(justify left bottom)
				(hide yes)
			)
		)
		(property "MPN" "GRM1555C1H102JA01D"
			(at 45.72 81.28 0)
			(effects
				(font
					(size 1.27 1.27)
					(thickness 0.15)
				)
				(justify left bottom)
				(hide yes)
			)
		)
		(property "Manufacturer" "Murata"
			(at 48.26 81.28 0)
			(effects
				(font
					(size 1.27 1.27)
					(thickness 0.15)
				)
				(justify left bottom)
				(hide yes)
			)
		)
		(property "License" "Apache-2.0"
			(at 50.8 81.28 0)
			(effects
				(font
					(size 1.27 1.27)
					(thickness 0.15)
				)
				(justify left bottom)
				(hide yes)
			)
		)
		(property "Author" "Antmicro"
			(at 53.34 81.28 0)
			(effects
				(font
					(size 1.27 1.27)
					(thickness 0.15)
				)
				(justify left bottom)
				(hide yes)
			)
		)
		(property "Val" "1n"
			(at 30.48 100.3236 90)
			(effects
				(font
					(size 1.27 1.27)
					(thickness 0.15)
				)
				(justify right)
			)
		)
		(property "Voltage" "50V"
			(at 55.88 81.28 0)
			(effects
				(font
					(size 1.27 1.27)
				)
				(justify left bottom)
				(hide yes)
			)
		)
		(property "Dielectric" "C0G"
			(at 58.42 81.28 0)
			(effects
				(font
					(size 1.27 1.27)
				)
				(justify left bottom)
				(hide yes)
			)
		)
		(pin "2"
		)
		(pin "1"
		)
		(instances
			(project ""
				(path ""
					(reference "C195")
					(unit 1)
				)
			)
		)
	)
	(symbol
		(lib_id "antmicroUSBConnectors:USB-C_Kycon_KUSBX-SL2-CS1N24-B-TR")
		(at 351.79 177.8 0)
		(mirror y)
		(unit 1)
		(exclude_from_sim no)
		(in_bom yes)
		(on_board yes)
		(dnp no)
		(property "Reference" "J5"
			(at 365.125 170.18 0)
			(effects
				(font
					(size 1.27 1.27)
					(thickness 0.15)
				)
			)
		)
		(property "Value" "USB-C_Kycon_KUSBX-SL2-CS1N24-B-TR"
			(at 308.61 182.88 0)
			(effects
				(font
					(size 1.27 1.27)
					(thickness 0.15)
				)
				(justify left bottom)
				(hide yes)
			)
		)
		(property "Footprint" "antmicro-footprints:USB-C_Receptacle_Kycon_KUSBX-SL2-CS1N24-B-TR"
			(at 308.61 185.42 0)
			(effects
				(font
					(size 1.27 1.27)
					(thickness 0.15)
				)
				(justify left bottom)
				(hide yes)
			)
		)
		(property "Datasheet" "https://www.kycon.com/Pub_Eng_Draw/KUSBX-SL2-CS1N24-B-TR.pdf"
			(at 308.61 187.96 0)
			(effects
				(font
					(size 1.27 1.27)
					(thickness 0.15)
				)
				(justify left bottom)
				(hide yes)
			)
		)
		(property "Description" "USB-C (USB TYPE-C) USB 3.2 Gen 2 (USB 3.1 Gen 2, Superspeed + (USB 3.1)) USB PD Receptacle Connector 24 Position Surface Mount"
			(at 308.61 200.66 0)
			(effects
				(font
					(size 1.27 1.27)
				)
				(justify left bottom)
				(hide yes)
			)
		)
		(property "MPN" "KUSBX-SL2-CS1N24-B-TR"
			(at 365.125 172.72 0)
			(effects
				(font
					(size 1.27 1.27)
					(thickness 0.15)
				)
			)
		)
		(property "Manufacturer" "Kycon"
			(at 308.61 193.04 0)
			(effects
				(font
					(size 1.27 1.27)
					(thickness 0.15)
				)
				(justify left bottom)
				(hide yes)
			)
		)
		(property "License" "Apache-2.0"
			(at 308.61 195.58 0)
			(effects
				(font
					(size 1.27 1.27)
					(thickness 0.15)
				)
				(justify left bottom)
				(hide yes)
			)
		)
		(property "Author" "Antmicro"
			(at 308.61 198.12 0)
			(effects
				(font
					(size 1.27 1.27)
					(thickness 0.15)
				)
				(justify left bottom)
				(hide yes)
			)
		)
		(pin "A6"
		)
		(pin "A2"
		)
		(pin "SH"
		)
		(pin "A1"
		)
		(pin "B12"
		)
		(pin "B7"
		)
		(pin "A12"
		)
		(pin "A8"
		)
		(pin "B1"
		)
		(pin "B8"
		)
		(pin "A3"
		)
		(pin "B10"
		)
		(pin "B3"
		)
		(pin "A7"
		)
		(pin "A11"
		)
		(pin "B5"
		)
		(pin "B9"
		)
		(pin "A5"
		)
		(pin "A9"
		)
		(pin "B4"
		)
		(pin "A4"
		)
		(pin "B6"
		)
		(pin "B2"
		)
		(pin "B11"
		)
		(pin "A10"
		)
		(instances
			(project "jetson-agx-thor-baseboard"
				(path ""
					(reference "J5")
					(unit 1)
				)
			)
		)
	)
	(symbol
		(lib_id "antmicropower:GND")
		(at 373.38 161.29 0)
		(unit 1)
		(exclude_from_sim no)
		(in_bom yes)
		(on_board yes)
		(dnp no)
		(property "Reference" "#PWR0467"
			(at 373.38 167.64 0)
			(effects
				(font
					(size 1.27 1.27)
				)
				(justify left bottom)
				(hide yes)
			)
		)
		(property "Value" "GND"
			(at 373.38 165.1 0)
			(effects
				(font
					(size 1.27 1.27)
					(thickness 0.15)
				)
			)
		)
		(property "Footprint" ""
			(at 382.27 168.91 0)
			(effects
				(font
					(size 1.27 1.27)
					(thickness 0.15)
				)
				(justify left bottom)
				(hide yes)
			)
		)
		(property "Datasheet" ""
			(at 382.27 173.99 0)
			(effects
				(font
					(size 1.27 1.27)
					(thickness 0.15)
				)
				(justify left bottom)
				(hide yes)
			)
		)
		(property "Description" ""
			(at 373.38 161.29 0)
			(effects
				(font
					(size 1.27 1.27)
				)
				(hide yes)
			)
		)
		(property "Author" "Antmicro"
			(at 382.27 168.91 0)
			(effects
				(font
					(size 1.27 1.27)
					(thickness 0.15)
				)
				(justify left bottom)
				(hide yes)
			)
		)
		(property "License" "Apache-2.0"
			(at 382.27 171.45 0)
			(effects
				(font
					(size 1.27 1.27)
					(thickness 0.15)
				)
				(justify left bottom)
				(hide yes)
			)
		)
		(pin "1"
		)
		(instances
			(project "jetson-agx-thor-baseboard"
				(path ""
					(reference "#PWR0467")
					(unit 1)
				)
			)
		)
	)
	(symbol
		(lib_id "antmicroTestPoints:TP_0.75mm_SMD")
		(at 114.3 121.92 180)
		(unit 1)
		(exclude_from_sim no)
		(in_bom no)
		(on_board yes)
		(dnp no)
		(property "Reference" "TP6"
			(at 110.236 121.158 0)
			(effects
				(font
					(size 1.27 1.27)
				)
				(justify left bottom)
			)
		)
		(property "Value" "TP_0.75mm_SMD"
			(at 104.14 118.11 0)
			(effects
				(font
					(size 1.27 1.27)
					(thickness 0.15)
				)
				(justify left bottom)
				(hide yes)
			)
		)
		(property "Footprint" "antmicro-footprints:TP_SMD_0.75mm"
			(at 104.14 115.57 0)
			(effects
				(font
					(size 1.27 1.27)
					(thickness 0.15)
				)
				(justify left bottom)
				(hide yes)
			)
		)
		(property "Datasheet" ""
			(at 96.52 109.22 0)
			(effects
				(font
					(size 1.27 1.27)
					(thickness 0.15)
				)
				(justify left bottom)
				(hide yes)
			)
		)
		(property "Description" "SMT test point"
			(at 114.3 121.92 0)
			(effects
				(font
					(size 1.27 1.27)
				)
				(hide yes)
			)
		)
		(property "MPN" ""
			(at 103.505 110.49 0)
			(effects
				(font
					(size 1.27 1.27)
					(thickness 0.15)
				)
				(justify left bottom)
				(hide yes)
			)
		)
		(property "Manufacturer" ""
			(at 103.505 115.57 0)
			(effects
				(font
					(size 1.27 1.27)
					(thickness 0.15)
				)
				(justify left bottom)
				(hide yes)
			)
		)
		(property "Author" "Antmicro"
			(at 104.14 113.03 0)
			(effects
				(font
					(size 1.27 1.27)
					(thickness 0.15)
				)
				(justify left bottom)
				(hide yes)
			)
		)
		(property "License" "Apache-2.0"
			(at 104.14 110.49 0)
			(effects
				(font
					(size 1.27 1.27)
					(thickness 0.15)
				)
				(justify left bottom)
				(hide yes)
			)
		)
		(pin "1"
		)
		(instances
			(project "jetson-agx-thor-baseboard"
				(path ""
					(reference "TP6")
					(unit 1)
				)
			)
		)
	)
	(symbol
		(lib_id "antmicroTestPoints:TP_0.75mm_SMD")
		(at 114.3 101.6 180)
		(unit 1)
		(exclude_from_sim no)
		(in_bom no)
		(on_board yes)
		(dnp no)
		(property "Reference" "TP66"
			(at 110.236 100.838 0)
			(effects
				(font
					(size 1.27 1.27)
				)
				(justify left bottom)
			)
		)
		(property "Value" "TP_0.75mm_SMD"
			(at 104.14 97.79 0)
			(effects
				(font
					(size 1.27 1.27)
					(thickness 0.15)
				)
				(justify left bottom)
				(hide yes)
			)
		)
		(property "Footprint" "antmicro-footprints:TP_SMD_0.75mm"
			(at 104.14 95.25 0)
			(effects
				(font
					(size 1.27 1.27)
					(thickness 0.15)
				)
				(justify left bottom)
				(hide yes)
			)
		)
		(property "Datasheet" ""
			(at 96.52 88.9 0)
			(effects
				(font
					(size 1.27 1.27)
					(thickness 0.15)
				)
				(justify left bottom)
				(hide yes)
			)
		)
		(property "Description" "SMT test point"
			(at 114.3 101.6 0)
			(effects
				(font
					(size 1.27 1.27)
				)
				(hide yes)
			)
		)
		(property "MPN" ""
			(at 103.505 90.17 0)
			(effects
				(font
					(size 1.27 1.27)
					(thickness 0.15)
				)
				(justify left bottom)
				(hide yes)
			)
		)
		(property "Manufacturer" ""
			(at 103.505 95.25 0)
			(effects
				(font
					(size 1.27 1.27)
					(thickness 0.15)
				)
				(justify left bottom)
				(hide yes)
			)
		)
		(property "Author" "Antmicro"
			(at 104.14 92.71 0)
			(effects
				(font
					(size 1.27 1.27)
					(thickness 0.15)
				)
				(justify left bottom)
				(hide yes)
			)
		)
		(property "License" "Apache-2.0"
			(at 104.14 90.17 0)
			(effects
				(font
					(size 1.27 1.27)
					(thickness 0.15)
				)
				(justify left bottom)
				(hide yes)
			)
		)
		(pin "1"
		)
		(instances
			(project "jetson-agx-thor-baseboard"
				(path ""
					(reference "TP66")
					(unit 1)
				)
			)
		)
	)
	(symbol
		(lib_id "antmicropower:+3V3")
		(at 201.93 142.24 0)
		(unit 1)
		(exclude_from_sim no)
		(in_bom yes)
		(on_board yes)
		(dnp no)
		(fields_autoplaced yes)
		(property "Reference" "#PWR0493"
			(at 217.17 142.24 0)
			(effects
				(font
					(size 1.27 1.27)
					(thickness 0.15)
				)
				(justify left bottom)
				(hide yes)
			)
		)
		(property "Value" "+3V3"
			(at 201.93 137.16 0)
			(effects
				(font
					(size 1.27 1.27)
					(thickness 0.15)
				)
			)
		)
		(property "Footprint" ""
			(at 217.17 149.86 0)
			(effects
				(font
					(size 1.27 1.27)
					(thickness 0.15)
				)
				(justify left bottom)
				(hide yes)
			)
		)
		(property "Datasheet" ""
			(at 217.17 152.4 0)
			(effects
				(font
					(size 1.27 1.27)
					(thickness 0.15)
				)
				(justify left bottom)
				(hide yes)
			)
		)
		(property "Description" ""
			(at 201.93 142.24 0)
			(effects
				(font
					(size 1.27 1.27)
				)
				(hide yes)
			)
		)
		(property "Author" "Antmicro"
			(at 217.17 144.78 0)
			(effects
				(font
					(size 1.27 1.27)
					(thickness 0.15)
				)
				(justify left bottom)
				(hide yes)
			)
		)
		(property "License" "Apache-2.0"
			(at 217.17 147.32 0)
			(effects
				(font
					(size 1.27 1.27)
					(thickness 0.15)
				)
				(justify left bottom)
				(hide yes)
			)
		)
		(pin "1"
		)
		(instances
			(project "jetson-agx-thor-baseboard"
				(path ""
					(reference "#PWR0493")
					(unit 1)
				)
			)
		)
	)
	(symbol
		(lib_id "antmicroCapacitors0402:C_100n_0402")
		(at 99.06 66.04 90)
		(unit 1)
		(exclude_from_sim no)
		(in_bom yes)
		(on_board yes)
		(dnp no)
		(fields_autoplaced yes)
		(property "Reference" "C96"
			(at 101.6 62.2236 90)
			(effects
				(font
					(size 1.27 1.27)
					(thickness 0.15)
				)
				(justify right)
			)
		)
		(property "Value" "C_100n_0402"
			(at 121.92 50.8 0)
			(effects
				(font
					(size 1.27 1.27)
					(thickness 0.15)
				)
				(justify left bottom)
				(hide yes)
			)
		)
		(property "Footprint" "antmicro-footprints:C_0402_1005Metric"
			(at 124.46 50.8 0)
			(effects
				(font
					(size 1.27 1.27)
					(thickness 0.15)
				)
				(justify left bottom)
				(hide yes)
			)
		)
		(property "Datasheet" "https://www.murata.com/products/productdetail?partno=GRM155R61H104KE14%23"
			(at 127 50.8 0)
			(effects
				(font
					(size 1.27 1.27)
					(thickness 0.15)
				)
				(justify left bottom)
				(hide yes)
			)
		)
		(property "Description" "SMD Multilayer Ceramic Capacitor, 0.1 µF, 50 V, 0402 [1005 Metric], ± 10%, X5R, GRM Series"
			(at 99.06 66.04 0)
			(effects
				(font
					(size 1.27 1.27)
				)
				(hide yes)
			)
		)
		(property "MPN" "GRM155R61H104KE14D"
			(at 129.54 50.8 0)
			(effects
				(font
					(size 1.27 1.27)
					(thickness 0.15)
				)
				(justify left bottom)
				(hide yes)
			)
		)
		(property "Val" "100n"
			(at 101.6 64.7636 90)
			(effects
				(font
					(size 1.27 1.27)
					(thickness 0.15)
				)
				(justify right)
			)
		)
		(property "Voltage" "50V"
			(at 109.22 50.8 0)
			(effects
				(font
					(size 1.27 1.27)
					(thickness 0.15)
				)
				(justify left bottom)
				(hide yes)
			)
		)
		(property "Dielectric" "X5R"
			(at 111.76 50.8 0)
			(effects
				(font
					(size 1.27 1.27)
					(thickness 0.15)
				)
				(justify left bottom)
				(hide yes)
			)
		)
		(property "Manufacturer" "Murata"
			(at 114.3 50.8 0)
			(effects
				(font
					(size 1.27 1.27)
					(thickness 0.15)
				)
				(justify left bottom)
				(hide yes)
			)
		)
		(property "License" "Apache-2.0"
			(at 116.84 50.8 0)
			(effects
				(font
					(size 1.27 1.27)
					(thickness 0.15)
				)
				(justify left bottom)
				(hide yes)
			)
		)
		(property "Author" "Antmicro"
			(at 119.38 50.8 0)
			(effects
				(font
					(size 1.27 1.27)
					(thickness 0.15)
				)
				(justify left bottom)
				(hide yes)
			)
		)
		(pin "1"
		)
		(pin "2"
		)
		(instances
			(project "jetson-agx-thor-baseboard"
				(path ""
					(reference "C96")
					(unit 1)
				)
			)
		)
	)
	(symbol
		(lib_id "antmicropower:GND")
		(at 17.78 68.58 0)
		(mirror y)
		(unit 1)
		(exclude_from_sim no)
		(in_bom yes)
		(on_board yes)
		(dnp no)
		(property "Reference" "#PWR0184"
			(at 17.78 74.93 0)
			(effects
				(font
					(size 1.27 1.27)
				)
				(justify left bottom)
				(hide yes)
			)
		)
		(property "Value" "GND"
			(at 17.78 72.39 0)
			(effects
				(font
					(size 1.27 1.27)
					(thickness 0.15)
				)
			)
		)
		(property "Footprint" ""
			(at 8.89 76.2 0)
			(effects
				(font
					(size 1.27 1.27)
					(thickness 0.15)
				)
				(justify left bottom)
				(hide yes)
			)
		)
		(property "Datasheet" ""
			(at 8.89 81.28 0)
			(effects
				(font
					(size 1.27 1.27)
					(thickness 0.15)
				)
				(justify left bottom)
				(hide yes)
			)
		)
		(property "Description" ""
			(at 17.78 68.58 0)
			(effects
				(font
					(size 1.27 1.27)
				)
				(hide yes)
			)
		)
		(property "Author" "Antmicro"
			(at 8.89 76.2 0)
			(effects
				(font
					(size 1.27 1.27)
					(thickness 0.15)
				)
				(justify left bottom)
				(hide yes)
			)
		)
		(property "License" "Apache-2.0"
			(at 8.89 78.74 0)
			(effects
				(font
					(size 1.27 1.27)
					(thickness 0.15)
				)
				(justify left bottom)
				(hide yes)
			)
		)
		(pin "1"
		)
		(instances
			(project "jetson-agx-thor-baseboard"
				(path ""
					(reference "#PWR0184")
					(unit 1)
				)
			)
		)
	)
	(symbol
		(lib_id "antmicroResistors0402:R_200k_0402")
		(at 228.6 195.58 270)
		(mirror x)
		(unit 1)
		(exclude_from_sim no)
		(in_bom yes)
		(on_board yes)
		(dnp no)
		(property "Reference" "R324"
			(at 227.584 191.77 90)
			(effects
				(font
					(size 1.27 1.27)
					(thickness 0.15)
				)
				(justify right)
			)
		)
		(property "Value" "R_200k_0402"
			(at 215.9 175.26 0)
			(effects
				(font
					(size 1.27 1.27)
					(thickness 0.15)
				)
				(justify left bottom)
				(hide yes)
			)
		)
		(property "Footprint" "antmicro-footprints:R_0402_1005Metric"
			(at 213.36 175.26 0)
			(effects
				(font
					(size 1.27 1.27)
					(thickness 0.15)
				)
				(justify left bottom)
				(hide yes)
			)
		)
		(property "Datasheet" "https://www.bourns.com/docs/product-datasheets/cr.pdf"
			(at 210.82 175.26 0)
			(effects
				(font
					(size 1.27 1.27)
					(thickness 0.15)
				)
				(justify left bottom)
				(hide yes)
			)
		)
		(property "Description" "SMD Chip Resistor, 200 kohm, ± 1%, 62.5 mW, 0402 [1005 Metric], Thick Film, General Purpose"
			(at 228.6 195.58 0)
			(effects
				(font
					(size 1.27 1.27)
				)
				(hide yes)
			)
		)
		(property "MPN" "CR0402-FX-2003GLF"
			(at 208.28 175.26 0)
			(effects
				(font
					(size 1.27 1.27)
					(thickness 0.15)
				)
				(justify left bottom)
				(hide yes)
			)
		)
		(property "Manufacturer" "Bourns"
			(at 205.74 175.26 0)
			(effects
				(font
					(size 1.27 1.27)
					(thickness 0.15)
				)
				(justify left bottom)
				(hide yes)
			)
		)
		(property "License" "Apache-2.0"
			(at 203.2 175.26 0)
			(effects
				(font
					(size 1.27 1.27)
					(thickness 0.15)
				)
				(justify left bottom)
				(hide yes)
			)
		)
		(property "Author" "Antmicro"
			(at 200.66 175.26 0)
			(effects
				(font
					(size 1.27 1.27)
					(thickness 0.15)
				)
				(justify left bottom)
				(hide yes)
			)
		)
		(property "Val" "200k"
			(at 227.584 194.31 90)
			(effects
				(font
					(size 1.27 1.27)
					(thickness 0.15)
				)
				(justify right)
			)
		)
		(property "Tolerance" "1%"
			(at 218.44 175.26 0)
			(effects
				(font
					(size 1.27 1.27)
				)
				(justify left bottom)
				(hide yes)
			)
		)
		(pin "1"
		)
		(pin "2"
		)
		(instances
			(project "jetson-agx-thor-baseboard"
				(path ""
					(reference "R324")
					(unit 1)
				)
			)
		)
	)
	(symbol
		(lib_id "antmicroInterfaceControllers:USB7252C")
		(at 127 62.23 0)
		(unit 1)
		(exclude_from_sim no)
		(in_bom yes)
		(on_board yes)
		(dnp no)
		(fields_autoplaced yes)
		(property "Reference" "U21"
			(at 154.94 54.61 0)
			(effects
				(font
					(size 1.27 1.27)
					(thickness 0.15)
				)
			)
		)
		(property "Value" "USB7252C"
			(at 189.23 71.12 0)
			(effects
				(font
					(size 1.27 1.27)
					(thickness 0.15)
				)
				(justify left bottom)
				(hide yes)
			)
		)
		(property "Footprint" "antmicro-footprints:VQFN-100-1EP_12x12x0.85mm_P0.4mm"
			(at 189.23 73.66 0)
			(effects
				(font
					(size 1.27 1.27)
					(thickness 0.15)
				)
				(justify left bottom)
				(hide yes)
			)
		)
		(property "Datasheet" "https://ww1.microchip.com/downloads/en/DeviceDoc/00003852A.pdf"
			(at 189.23 76.2 0)
			(effects
				(font
					(size 1.27 1.27)
					(thickness 0.15)
				)
				(justify left bottom)
				(hide yes)
			)
		)
		(property "Description" "4-Port USB 3.2 Hub, 2x Type-C with Power Delivery support, 1x USB 3.2, 1x USB 2.0"
			(at 189.23 78.74 0)
			(effects
				(font
					(size 1.27 1.27)
					(thickness 0.15)
				)
				(justify left bottom)
				(hide yes)
			)
		)
		(property "MPN" "USB7252CT-I/KDX "
			(at 154.94 57.15 0)
			(effects
				(font
					(size 1.27 1.27)
					(thickness 0.15)
				)
			)
		)
		(property "Manufacturer" "Microchip Technology"
			(at 189.23 81.28 0)
			(effects
				(font
					(size 1.27 1.27)
					(thickness 0.15)
				)
				(justify left bottom)
				(hide yes)
			)
		)
		(property "Author" "Antmicro"
			(at 189.23 83.82 0)
			(effects
				(font
					(size 1.27 1.27)
					(thickness 0.15)
				)
				(justify left bottom)
				(hide yes)
			)
		)
		(property "License" "Apache-2.0"
			(at 189.23 86.36 0)
			(effects
				(font
					(size 1.27 1.27)
					(thickness 0.15)
				)
				(justify left bottom)
				(hide yes)
			)
		)
		(pin "44"
		)
		(pin "5"
		)
		(pin "36"
		)
		(pin "37"
		)
		(pin "32"
		)
		(pin "38"
		)
		(pin "34"
		)
		(pin "57"
		)
		(pin "98"
		)
		(pin "17"
		)
		(pin "23"
		)
		(pin "96"
		)
		(pin "65"
		)
		(pin "77"
		)
		(pin "27"
		)
		(pin "45"
		)
		(pin "95"
		)
		(pin "51"
		)
		(pin "39"
		)
		(pin "85"
		)
		(pin "72"
		)
		(pin "58"
		)
		(pin "71"
		)
		(pin "19"
		)
		(pin "101"
		)
		(pin "86"
		)
		(pin "54"
		)
		(pin "48"
		)
		(pin "82"
		)
		(pin "80"
		)
		(pin "10"
		)
		(pin "1"
		)
		(pin "14"
		)
		(pin "20"
		)
		(pin "2"
		)
		(pin "50"
		)
		(pin "83"
		)
		(pin "49"
		)
		(pin "8"
		)
		(pin "21"
		)
		(pin "43"
		)
		(pin "74"
		)
		(pin "15"
		)
		(pin "11"
		)
		(pin "76"
		)
		(pin "94"
		)
		(pin "28"
		)
		(pin "30"
		)
		(pin "41"
		)
		(pin "97"
		)
		(pin "16"
		)
		(pin "63"
		)
		(pin "26"
		)
		(pin "40"
		)
		(pin "53"
		)
		(pin "73"
		)
		(pin "24"
		)
		(pin "90"
		)
		(pin "100"
		)
		(pin "64"
		)
		(pin "61"
		)
		(pin "29"
		)
		(pin "84"
		)
		(pin "92"
		)
		(pin "87"
		)
		(pin "47"
		)
		(pin "35"
		)
		(pin "31"
		)
		(pin "42"
		)
		(pin "46"
		)
		(pin "99"
		)
		(pin "52"
		)
		(pin "75"
		)
		(pin "3"
		)
		(pin "66"
		)
		(pin "93"
		)
		(pin "13"
		)
		(pin "25"
		)
		(pin "6"
		)
		(pin "60"
		)
		(pin "68"
		)
		(pin "12"
		)
		(pin "4"
		)
		(pin "7"
		)
		(pin "59"
		)
		(pin "81"
		)
		(pin "55"
		)
		(pin "78"
		)
		(pin "9"
		)
		(pin "18"
		)
		(pin "70"
		)
		(pin "69"
		)
		(pin "22"
		)
		(pin "67"
		)
		(pin "88"
		)
		(pin "79"
		)
		(pin "56"
		)
		(pin "89"
		)
		(pin "33"
		)
		(pin "91"
		)
		(pin "62"
		)
		(instances
			(project "jetson-agx-thor-baseboard"
				(path ""
					(reference "U21")
					(unit 1)
				)
			)
		)
	)
	(symbol
		(lib_id "antmicroResistors0402:R_200k_0402")
		(at 35.56 196.85 90)
		(unit 1)
		(exclude_from_sim no)
		(in_bom yes)
		(on_board yes)
		(dnp no)
		(property "Reference" "R80"
			(at 36.576 193.04 90)
			(effects
				(font
					(size 1.27 1.27)
					(thickness 0.15)
				)
				(justify right)
			)
		)
		(property "Value" "R_200k_0402"
			(at 48.26 176.53 0)
			(effects
				(font
					(size 1.27 1.27)
					(thickness 0.15)
				)
				(justify left bottom)
				(hide yes)
			)
		)
		(property "Footprint" "antmicro-footprints:R_0402_1005Metric"
			(at 50.8 176.53 0)
			(effects
				(font
					(size 1.27 1.27)
					(thickness 0.15)
				)
				(justify left bottom)
				(hide yes)
			)
		)
		(property "Datasheet" "https://www.bourns.com/docs/product-datasheets/cr.pdf"
			(at 53.34 176.53 0)
			(effects
				(font
					(size 1.27 1.27)
					(thickness 0.15)
				)
				(justify left bottom)
				(hide yes)
			)
		)
		(property "Description" "SMD Chip Resistor, 200 kohm, ± 1%, 62.5 mW, 0402 [1005 Metric], Thick Film, General Purpose"
			(at 35.56 196.85 0)
			(effects
				(font
					(size 1.27 1.27)
				)
				(hide yes)
			)
		)
		(property "MPN" "CR0402-FX-2003GLF"
			(at 55.88 176.53 0)
			(effects
				(font
					(size 1.27 1.27)
					(thickness 0.15)
				)
				(justify left bottom)
				(hide yes)
			)
		)
		(property "Manufacturer" "Bourns"
			(at 58.42 176.53 0)
			(effects
				(font
					(size 1.27 1.27)
					(thickness 0.15)
				)
				(justify left bottom)
				(hide yes)
			)
		)
		(property "License" "Apache-2.0"
			(at 60.96 176.53 0)
			(effects
				(font
					(size 1.27 1.27)
					(thickness 0.15)
				)
				(justify left bottom)
				(hide yes)
			)
		)
		(property "Author" "Antmicro"
			(at 63.5 176.53 0)
			(effects
				(font
					(size 1.27 1.27)
					(thickness 0.15)
				)
				(justify left bottom)
				(hide yes)
			)
		)
		(property "Val" "200k"
			(at 36.576 195.58 90)
			(effects
				(font
					(size 1.27 1.27)
					(thickness 0.15)
				)
				(justify right)
			)
		)
		(property "Tolerance" "1%"
			(at 45.72 176.53 0)
			(effects
				(font
					(size 1.27 1.27)
				)
				(justify left bottom)
				(hide yes)
			)
		)
		(pin "1"
		)
		(pin "2"
		)
		(instances
			(project "jetson-agx-thor-baseboard"
				(path ""
					(reference "R80")
					(unit 1)
				)
			)
		)
	)
	(symbol
		(lib_id "antmicroCapacitors0402:C_100n_0402")
		(at 285.75 104.14 180)
		(unit 1)
		(exclude_from_sim no)
		(in_bom yes)
		(on_board yes)
		(dnp no)
		(property "Reference" "C102"
			(at 289.56 102.108 0)
			(effects
				(font
					(size 1.27 1.27)
				)
				(justify left bottom)
			)
		)
		(property "Value" "C_100n_0402"
			(at 265.43 93.98 0)
			(effects
				(font
					(size 1.27 1.27)
					(thickness 0.15)
				)
				(justify left bottom)
				(hide yes)
			)
		)
		(property "Footprint" "antmicro-footprints:C_0402_1005Metric"
			(at 265.43 91.44 0)
			(effects
				(font
					(size 1.27 1.27)
					(thickness 0.15)
				)
				(justify left bottom)
				(hide yes)
			)
		)
		(property "Datasheet" "https://www.murata.com/products/productdetail?partno=GRM155R61H104KE14%23"
			(at 265.43 88.9 0)
			(effects
				(font
					(size 1.27 1.27)
					(thickness 0.15)
				)
				(justify left bottom)
				(hide yes)
			)
		)
		(property "Description" "SMD Multilayer Ceramic Capacitor, 0.1 µF, 50 V, 0402 [1005 Metric], ± 10%, X5R, GRM Series"
			(at 285.75 104.14 0)
			(effects
				(font
					(size 1.27 1.27)
				)
				(hide yes)
			)
		)
		(property "Manufacturer" "Murata"
			(at 265.43 83.82 0)
			(effects
				(font
					(size 1.27 1.27)
					(thickness 0.15)
				)
				(justify left bottom)
				(hide yes)
			)
		)
		(property "MPN" "GRM155R61H104KE14D"
			(at 265.43 86.36 0)
			(effects
				(font
					(size 1.27 1.27)
					(thickness 0.15)
				)
				(justify left bottom)
				(hide yes)
			)
		)
		(property "Val" "100n"
			(at 281.94 104.775 0)
			(effects
				(font
					(size 1.27 1.27)
					(thickness 0.15)
				)
				(justify left bottom)
			)
		)
		(property "License" "Apache-2.0"
			(at 265.43 81.28 0)
			(effects
				(font
					(size 1.27 1.27)
					(thickness 0.15)
				)
				(justify left bottom)
				(hide yes)
			)
		)
		(property "Author" "Antmicro"
			(at 265.43 78.74 0)
			(effects
				(font
					(size 1.27 1.27)
					(thickness 0.15)
				)
				(justify left bottom)
				(hide yes)
			)
		)
		(property "Voltage" "50V"
			(at 265.43 76.2 0)
			(effects
				(font
					(size 1.27 1.27)
				)
				(justify left bottom)
				(hide yes)
			)
		)
		(property "Dielectric" "X5R"
			(at 265.43 73.66 0)
			(effects
				(font
					(size 1.27 1.27)
				)
				(justify left bottom)
				(hide yes)
			)
		)
		(pin "1"
		)
		(pin "2"
		)
		(instances
			(project "jetson-agx-thor-baseboard"
				(path ""
					(reference "C102")
					(unit 1)
				)
			)
		)
	)
	(symbol
		(lib_id "antmicroCapacitors0402:C_100n_0402")
		(at 58.42 66.04 90)
		(unit 1)
		(exclude_from_sim no)
		(in_bom yes)
		(on_board yes)
		(dnp no)
		(fields_autoplaced yes)
		(property "Reference" "C87"
			(at 60.96 62.2236 90)
			(effects
				(font
					(size 1.27 1.27)
					(thickness 0.15)
				)
				(justify right)
			)
		)
		(property "Value" "C_100n_0402"
			(at 81.28 50.8 0)
			(effects
				(font
					(size 1.27 1.27)
					(thickness 0.15)
				)
				(justify left bottom)
				(hide yes)
			)
		)
		(property "Footprint" "antmicro-footprints:C_0402_1005Metric"
			(at 83.82 50.8 0)
			(effects
				(font
					(size 1.27 1.27)
					(thickness 0.15)
				)
				(justify left bottom)
				(hide yes)
			)
		)
		(property "Datasheet" "https://www.murata.com/products/productdetail?partno=GRM155R61H104KE14%23"
			(at 86.36 50.8 0)
			(effects
				(font
					(size 1.27 1.27)
					(thickness 0.15)
				)
				(justify left bottom)
				(hide yes)
			)
		)
		(property "Description" "SMD Multilayer Ceramic Capacitor, 0.1 µF, 50 V, 0402 [1005 Metric], ± 10%, X5R, GRM Series"
			(at 58.42 66.04 0)
			(effects
				(font
					(size 1.27 1.27)
				)
				(hide yes)
			)
		)
		(property "MPN" "GRM155R61H104KE14D"
			(at 88.9 50.8 0)
			(effects
				(font
					(size 1.27 1.27)
					(thickness 0.15)
				)
				(justify left bottom)
				(hide yes)
			)
		)
		(property "Val" "100n"
			(at 60.96 64.7636 90)
			(effects
				(font
					(size 1.27 1.27)
					(thickness 0.15)
				)
				(justify right)
			)
		)
		(property "Voltage" "50V"
			(at 68.58 50.8 0)
			(effects
				(font
					(size 1.27 1.27)
					(thickness 0.15)
				)
				(justify left bottom)
				(hide yes)
			)
		)
		(property "Dielectric" "X5R"
			(at 71.12 50.8 0)
			(effects
				(font
					(size 1.27 1.27)
					(thickness 0.15)
				)
				(justify left bottom)
				(hide yes)
			)
		)
		(property "Manufacturer" "Murata"
			(at 73.66 50.8 0)
			(effects
				(font
					(size 1.27 1.27)
					(thickness 0.15)
				)
				(justify left bottom)
				(hide yes)
			)
		)
		(property "License" "Apache-2.0"
			(at 76.2 50.8 0)
			(effects
				(font
					(size 1.27 1.27)
					(thickness 0.15)
				)
				(justify left bottom)
				(hide yes)
			)
		)
		(property "Author" "Antmicro"
			(at 78.74 50.8 0)
			(effects
				(font
					(size 1.27 1.27)
					(thickness 0.15)
				)
				(justify left bottom)
				(hide yes)
			)
		)
		(pin "1"
		)
		(pin "2"
		)
		(instances
			(project "jetson-agx-thor-baseboard"
				(path ""
					(reference "C87")
					(unit 1)
				)
			)
		)
	)
	(symbol
		(lib_id "antmicroCapacitors0402:C_100n_0402")
		(at 109.22 66.04 90)
		(unit 1)
		(exclude_from_sim no)
		(in_bom yes)
		(on_board yes)
		(dnp no)
		(property "Reference" "C98"
			(at 110.744 62.23 90)
			(effects
				(font
					(size 1.27 1.27)
					(thickness 0.15)
				)
				(justify right)
			)
		)
		(property "Value" "C_100n_0402"
			(at 132.08 50.8 0)
			(effects
				(font
					(size 1.27 1.27)
					(thickness 0.15)
				)
				(justify left bottom)
				(hide yes)
			)
		)
		(property "Footprint" "antmicro-footprints:C_0402_1005Metric"
			(at 134.62 50.8 0)
			(effects
				(font
					(size 1.27 1.27)
					(thickness 0.15)
				)
				(justify left bottom)
				(hide yes)
			)
		)
		(property "Datasheet" "https://www.murata.com/products/productdetail?partno=GRM155R61H104KE14%23"
			(at 137.16 50.8 0)
			(effects
				(font
					(size 1.27 1.27)
					(thickness 0.15)
				)
				(justify left bottom)
				(hide yes)
			)
		)
		(property "Description" "SMD Multilayer Ceramic Capacitor, 0.1 µF, 50 V, 0402 [1005 Metric], ± 10%, X5R, GRM Series"
			(at 109.22 66.04 0)
			(effects
				(font
					(size 1.27 1.27)
				)
				(hide yes)
			)
		)
		(property "MPN" "GRM155R61H104KE14D"
			(at 139.7 50.8 0)
			(effects
				(font
					(size 1.27 1.27)
					(thickness 0.15)
				)
				(justify left bottom)
				(hide yes)
			)
		)
		(property "Val" "100n"
			(at 110.998 64.262 90)
			(effects
				(font
					(size 1.27 1.27)
					(thickness 0.15)
				)
				(justify right)
			)
		)
		(property "Voltage" "50V"
			(at 119.38 50.8 0)
			(effects
				(font
					(size 1.27 1.27)
					(thickness 0.15)
				)
				(justify left bottom)
				(hide yes)
			)
		)
		(property "Dielectric" "X5R"
			(at 121.92 50.8 0)
			(effects
				(font
					(size 1.27 1.27)
					(thickness 0.15)
				)
				(justify left bottom)
				(hide yes)
			)
		)
		(property "Manufacturer" "Murata"
			(at 124.46 50.8 0)
			(effects
				(font
					(size 1.27 1.27)
					(thickness 0.15)
				)
				(justify left bottom)
				(hide yes)
			)
		)
		(property "License" "Apache-2.0"
			(at 127 50.8 0)
			(effects
				(font
					(size 1.27 1.27)
					(thickness 0.15)
				)
				(justify left bottom)
				(hide yes)
			)
		)
		(property "Author" "Antmicro"
			(at 129.54 50.8 0)
			(effects
				(font
					(size 1.27 1.27)
					(thickness 0.15)
				)
				(justify left bottom)
				(hide yes)
			)
		)
		(pin "1"
		)
		(pin "2"
		)
		(instances
			(project "jetson-agx-thor-baseboard"
				(path ""
					(reference "C98")
					(unit 1)
				)
			)
		)
	)
	(symbol
		(lib_id "antmicropower:GND")
		(at 350.52 245.11 0)
		(mirror y)
		(unit 1)
		(exclude_from_sim no)
		(in_bom yes)
		(on_board yes)
		(dnp no)
		(property "Reference" "#PWR0211"
			(at 350.52 251.46 0)
			(effects
				(font
					(size 1.27 1.27)
				)
				(justify left bottom)
				(hide yes)
			)
		)
		(property "Value" "GND"
			(at 350.52 248.92 0)
			(effects
				(font
					(size 1.27 1.27)
					(thickness 0.15)
				)
			)
		)
		(property "Footprint" ""
			(at 341.63 252.73 0)
			(effects
				(font
					(size 1.27 1.27)
					(thickness 0.15)
				)
				(justify left bottom)
				(hide yes)
			)
		)
		(property "Datasheet" ""
			(at 341.63 257.81 0)
			(effects
				(font
					(size 1.27 1.27)
					(thickness 0.15)
				)
				(justify left bottom)
				(hide yes)
			)
		)
		(property "Description" ""
			(at 350.52 245.11 0)
			(effects
				(font
					(size 1.27 1.27)
				)
				(hide yes)
			)
		)
		(property "Author" "Antmicro"
			(at 341.63 252.73 0)
			(effects
				(font
					(size 1.27 1.27)
					(thickness 0.15)
				)
				(justify left bottom)
				(hide yes)
			)
		)
		(property "License" "Apache-2.0"
			(at 341.63 255.27 0)
			(effects
				(font
					(size 1.27 1.27)
					(thickness 0.15)
				)
				(justify left bottom)
				(hide yes)
			)
		)
		(pin "1"
		)
		(instances
			(project "jetson-agx-thor-baseboard"
				(path ""
					(reference "#PWR0211")
					(unit 1)
				)
			)
		)
	)
	(symbol
		(lib_id "antmicropower:GND")
		(at 350.52 123.19 0)
		(mirror y)
		(unit 1)
		(exclude_from_sim no)
		(in_bom yes)
		(on_board yes)
		(dnp no)
		(property "Reference" "#PWR0212"
			(at 350.52 129.54 0)
			(effects
				(font
					(size 1.27 1.27)
				)
				(justify left bottom)
				(hide yes)
			)
		)
		(property "Value" "GND"
			(at 350.52 127 0)
			(effects
				(font
					(size 1.27 1.27)
					(thickness 0.15)
				)
			)
		)
		(property "Footprint" ""
			(at 341.63 130.81 0)
			(effects
				(font
					(size 1.27 1.27)
					(thickness 0.15)
				)
				(justify left bottom)
				(hide yes)
			)
		)
		(property "Datasheet" ""
			(at 341.63 135.89 0)
			(effects
				(font
					(size 1.27 1.27)
					(thickness 0.15)
				)
				(justify left bottom)
				(hide yes)
			)
		)
		(property "Description" ""
			(at 350.52 123.19 0)
			(effects
				(font
					(size 1.27 1.27)
				)
				(hide yes)
			)
		)
		(property "Author" "Antmicro"
			(at 341.63 130.81 0)
			(effects
				(font
					(size 1.27 1.27)
					(thickness 0.15)
				)
				(justify left bottom)
				(hide yes)
			)
		)
		(property "License" "Apache-2.0"
			(at 341.63 133.35 0)
			(effects
				(font
					(size 1.27 1.27)
					(thickness 0.15)
				)
				(justify left bottom)
				(hide yes)
			)
		)
		(pin "1"
		)
		(instances
			(project "jetson-agx-thor-baseboard"
				(path ""
					(reference "#PWR0212")
					(unit 1)
				)
			)
		)
	)
	(symbol
		(lib_id "antmicroResistors0402:R_100k_0402")
		(at 220.98 195.58 270)
		(mirror x)
		(unit 1)
		(exclude_from_sim no)
		(in_bom yes)
		(on_board yes)
		(dnp no)
		(property "Reference" "R325"
			(at 219.71 191.77 90)
			(effects
				(font
					(size 1.27 1.27)
					(thickness 0.15)
				)
				(justify right)
			)
		)
		(property "Value" "R_100k_0402"
			(at 208.28 175.26 0)
			(effects
				(font
					(size 1.27 1.27)
					(thickness 0.15)
				)
				(justify left bottom)
				(hide yes)
			)
		)
		(property "Footprint" "antmicro-footprints:R_0402_1005Metric"
			(at 205.74 175.26 0)
			(effects
				(font
					(size 1.27 1.27)
					(thickness 0.15)
				)
				(justify left bottom)
				(hide yes)
			)
		)
		(property "Datasheet" "https://www.bourns.com/docs/product-datasheets/cr.pdf"
			(at 203.2 175.26 0)
			(effects
				(font
					(size 1.27 1.27)
					(thickness 0.15)
				)
				(justify left bottom)
				(hide yes)
			)
		)
		(property "Description" "SMD Chip Resistor, 100 kohm, ± 1%, 62.5 mW, 0402 [1005 Metric], Thick Film, General Purpose"
			(at 190.5 175.26 0)
			(effects
				(font
					(size 1.27 1.27)
				)
				(justify left bottom)
				(hide yes)
			)
		)
		(property "MPN" "CR0402-FX-1003GLF"
			(at 200.66 175.26 0)
			(effects
				(font
					(size 1.27 1.27)
					(thickness 0.15)
				)
				(justify left bottom)
				(hide yes)
			)
		)
		(property "Manufacturer" "Bourns"
			(at 198.12 175.26 0)
			(effects
				(font
					(size 1.27 1.27)
					(thickness 0.15)
				)
				(justify left bottom)
				(hide yes)
			)
		)
		(property "License" "Apache-2.0"
			(at 195.58 175.26 0)
			(effects
				(font
					(size 1.27 1.27)
					(thickness 0.15)
				)
				(justify left bottom)
				(hide yes)
			)
		)
		(property "Author" "Antmicro"
			(at 193.04 175.26 0)
			(effects
				(font
					(size 1.27 1.27)
					(thickness 0.15)
				)
				(justify left bottom)
				(hide yes)
			)
		)
		(property "Val" "100k"
			(at 219.71 194.31 90)
			(effects
				(font
					(size 1.27 1.27)
					(thickness 0.15)
				)
				(justify right)
			)
		)
		(property "Tolerance" "1%"
			(at 210.82 175.26 0)
			(effects
				(font
					(size 1.27 1.27)
				)
				(justify left bottom)
				(hide yes)
			)
		)
		(pin "2"
		)
		(pin "1"
		)
		(instances
			(project "jetson-agx-thor-baseboard"
				(path ""
					(reference "R325")
					(unit 1)
				)
			)
		)
	)
	(symbol
		(lib_id "antmicroCapacitors0402:C_100n_0402")
		(at 88.9 66.04 90)
		(unit 1)
		(exclude_from_sim no)
		(in_bom yes)
		(on_board yes)
		(dnp no)
		(fields_autoplaced yes)
		(property "Reference" "C94"
			(at 91.44 62.2236 90)
			(effects
				(font
					(size 1.27 1.27)
					(thickness 0.15)
				)
				(justify right)
			)
		)
		(property "Value" "C_100n_0402"
			(at 111.76 50.8 0)
			(effects
				(font
					(size 1.27 1.27)
					(thickness 0.15)
				)
				(justify left bottom)
				(hide yes)
			)
		)
		(property "Footprint" "antmicro-footprints:C_0402_1005Metric"
			(at 114.3 50.8 0)
			(effects
				(font
					(size 1.27 1.27)
					(thickness 0.15)
				)
				(justify left bottom)
				(hide yes)
			)
		)
		(property "Datasheet" "https://www.murata.com/products/productdetail?partno=GRM155R61H104KE14%23"
			(at 116.84 50.8 0)
			(effects
				(font
					(size 1.27 1.27)
					(thickness 0.15)
				)
				(justify left bottom)
				(hide yes)
			)
		)
		(property "Description" "SMD Multilayer Ceramic Capacitor, 0.1 µF, 50 V, 0402 [1005 Metric], ± 10%, X5R, GRM Series"
			(at 88.9 66.04 0)
			(effects
				(font
					(size 1.27 1.27)
				)
				(hide yes)
			)
		)
		(property "MPN" "GRM155R61H104KE14D"
			(at 119.38 50.8 0)
			(effects
				(font
					(size 1.27 1.27)
					(thickness 0.15)
				)
				(justify left bottom)
				(hide yes)
			)
		)
		(property "Val" "100n"
			(at 91.44 64.7636 90)
			(effects
				(font
					(size 1.27 1.27)
					(thickness 0.15)
				)
				(justify right)
			)
		)
		(property "Voltage" "50V"
			(at 99.06 50.8 0)
			(effects
				(font
					(size 1.27 1.27)
					(thickness 0.15)
				)
				(justify left bottom)
				(hide yes)
			)
		)
		(property "Dielectric" "X5R"
			(at 101.6 50.8 0)
			(effects
				(font
					(size 1.27 1.27)
					(thickness 0.15)
				)
				(justify left bottom)
				(hide yes)
			)
		)
		(property "Manufacturer" "Murata"
			(at 104.14 50.8 0)
			(effects
				(font
					(size 1.27 1.27)
					(thickness 0.15)
				)
				(justify left bottom)
				(hide yes)
			)
		)
		(property "License" "Apache-2.0"
			(at 106.68 50.8 0)
			(effects
				(font
					(size 1.27 1.27)
					(thickness 0.15)
				)
				(justify left bottom)
				(hide yes)
			)
		)
		(property "Author" "Antmicro"
			(at 109.22 50.8 0)
			(effects
				(font
					(size 1.27 1.27)
					(thickness 0.15)
				)
				(justify left bottom)
				(hide yes)
			)
		)
		(pin "1"
		)
		(pin "2"
		)
		(instances
			(project "jetson-agx-thor-baseboard"
				(path ""
					(reference "C94")
					(unit 1)
				)
			)
		)
	)
	(symbol
		(lib_id "antmicroResistors0402:R_2R2_0402")
		(at 234.95 231.14 0)
		(unit 1)
		(exclude_from_sim no)
		(in_bom yes)
		(on_board yes)
		(dnp no)
		(property "Reference" "R336"
			(at 237.236 228.854 0)
			(effects
				(font
					(size 1.27 1.27)
					(thickness 0.15)
				)
			)
		)
		(property "Value" "R_2R2_0402"
			(at 255.27 243.84 0)
			(effects
				(font
					(size 1.27 1.27)
					(thickness 0.15)
				)
				(justify left bottom)
				(hide yes)
			)
		)
		(property "Footprint" "antmicro-footprints:R_0402_1005Metric"
			(at 255.27 246.38 0)
			(effects
				(font
					(size 1.27 1.27)
					(thickness 0.15)
				)
				(justify left bottom)
				(hide yes)
			)
		)
		(property "Datasheet" "https://www.bourns.com/docs/product-datasheets/cr.pdf"
			(at 255.27 248.92 0)
			(effects
				(font
					(size 1.27 1.27)
					(thickness 0.15)
				)
				(justify left bottom)
				(hide yes)
			)
		)
		(property "Description" "SMD Chip Resistor, 2.2 ohm, ± 1%, 62.5 mW, 0402 [1005 Metric], Thick Film, General Purpose"
			(at 255.27 261.62 0)
			(effects
				(font
					(size 1.27 1.27)
				)
				(justify left bottom)
				(hide yes)
			)
		)
		(property "MPN" "CR0402-FX-2R20GLF"
			(at 255.27 251.46 0)
			(effects
				(font
					(size 1.27 1.27)
					(thickness 0.15)
				)
				(justify left bottom)
				(hide yes)
			)
		)
		(property "Manufacturer" "Bourns"
			(at 255.27 254 0)
			(effects
				(font
					(size 1.27 1.27)
					(thickness 0.15)
				)
				(justify left bottom)
				(hide yes)
			)
		)
		(property "License" "Apache-2.0"
			(at 255.27 256.54 0)
			(effects
				(font
					(size 1.27 1.27)
					(thickness 0.15)
				)
				(justify left bottom)
				(hide yes)
			)
		)
		(property "Author" "Antmicro"
			(at 255.27 259.08 0)
			(effects
				(font
					(size 1.27 1.27)
					(thickness 0.15)
				)
				(justify left bottom)
				(hide yes)
			)
		)
		(property "Val" "2R2"
			(at 237.236 233.426 0)
			(effects
				(font
					(size 1.27 1.27)
					(thickness 0.15)
				)
			)
		)
		(property "Tolerance" "1%"
			(at 255.27 241.3 0)
			(effects
				(font
					(size 1.27 1.27)
				)
				(justify left bottom)
				(hide yes)
			)
		)
		(pin "2"
		)
		(pin "1"
		)
		(instances
			(project "jetson-agx-thor-baseboard"
				(path ""
					(reference "R336")
					(unit 1)
				)
			)
		)
	)
	(symbol
		(lib_id "antmicropower:GND")
		(at 226.06 242.57 0)
		(mirror y)
		(unit 1)
		(exclude_from_sim no)
		(in_bom yes)
		(on_board yes)
		(dnp no)
		(property "Reference" "#PWR0684"
			(at 226.06 248.92 0)
			(effects
				(font
					(size 1.27 1.27)
				)
				(justify left bottom)
				(hide yes)
			)
		)
		(property "Value" "GND"
			(at 226.06 246.38 0)
			(effects
				(font
					(size 1.27 1.27)
					(thickness 0.15)
				)
			)
		)
		(property "Footprint" ""
			(at 217.17 250.19 0)
			(effects
				(font
					(size 1.27 1.27)
					(thickness 0.15)
				)
				(justify left bottom)
				(hide yes)
			)
		)
		(property "Datasheet" ""
			(at 217.17 255.27 0)
			(effects
				(font
					(size 1.27 1.27)
					(thickness 0.15)
				)
				(justify left bottom)
				(hide yes)
			)
		)
		(property "Description" ""
			(at 226.06 242.57 0)
			(effects
				(font
					(size 1.27 1.27)
				)
				(hide yes)
			)
		)
		(property "Author" "Antmicro"
			(at 217.17 250.19 0)
			(effects
				(font
					(size 1.27 1.27)
					(thickness 0.15)
				)
				(justify left bottom)
				(hide yes)
			)
		)
		(property "License" "Apache-2.0"
			(at 217.17 252.73 0)
			(effects
				(font
					(size 1.27 1.27)
					(thickness 0.15)
				)
				(justify left bottom)
				(hide yes)
			)
		)
		(pin "1"
		)
		(instances
			(project "jetson-agx-thor-baseboard"
				(path ""
					(reference "#PWR0684")
					(unit 1)
				)
			)
		)
	)
	(symbol
		(lib_id "antmicropower:GND")
		(at 208.28 69.85 0)
		(unit 1)
		(exclude_from_sim no)
		(in_bom yes)
		(on_board yes)
		(dnp no)
		(property "Reference" "#PWR0469"
			(at 208.28 76.2 0)
			(effects
				(font
					(size 1.27 1.27)
				)
				(justify left bottom)
				(hide yes)
			)
		)
		(property "Value" "GND"
			(at 208.28 73.66 0)
			(effects
				(font
					(size 1.27 1.27)
					(thickness 0.15)
				)
			)
		)
		(property "Footprint" ""
			(at 217.17 77.47 0)
			(effects
				(font
					(size 1.27 1.27)
					(thickness 0.15)
				)
				(justify left bottom)
				(hide yes)
			)
		)
		(property "Datasheet" ""
			(at 217.17 82.55 0)
			(effects
				(font
					(size 1.27 1.27)
					(thickness 0.15)
				)
				(justify left bottom)
				(hide yes)
			)
		)
		(property "Description" ""
			(at 208.28 69.85 0)
			(effects
				(font
					(size 1.27 1.27)
				)
				(hide yes)
			)
		)
		(property "Author" "Antmicro"
			(at 217.17 77.47 0)
			(effects
				(font
					(size 1.27 1.27)
					(thickness 0.15)
				)
				(justify left bottom)
				(hide yes)
			)
		)
		(property "License" "Apache-2.0"
			(at 217.17 80.01 0)
			(effects
				(font
					(size 1.27 1.27)
					(thickness 0.15)
				)
				(justify left bottom)
				(hide yes)
			)
		)
		(pin "1"
		)
		(instances
			(project "jetson-agx-thor-baseboard"
				(path ""
					(reference "#PWR0469")
					(unit 1)
				)
			)
		)
	)
	(symbol
		(lib_id "antmicroCapacitors0603:C_22u_16V_0603")
		(at 17.78 66.04 90)
		(unit 1)
		(exclude_from_sim no)
		(in_bom yes)
		(on_board yes)
		(dnp no)
		(fields_autoplaced yes)
		(property "Reference" "C312"
			(at 20.32 62.2235 90)
			(effects
				(font
					(size 1.27 1.27)
				)
				(justify right)
			)
		)
		(property "Value" "C_22u_16V_0603"
			(at 27.94 45.72 0)
			(effects
				(font
					(size 1.27 1.27)
					(thickness 0.15)
				)
				(justify left bottom)
				(hide yes)
			)
		)
		(property "Footprint" "antmicro-footprints:C_0603_1608Metric_EIA"
			(at 30.48 45.72 0)
			(effects
				(font
					(size 1.27 1.27)
					(thickness 0.15)
				)
				(justify left bottom)
				(hide yes)
			)
		)
		(property "Datasheet" "https://product.samsungsem.com/mlcc/CL10A226MO7JZN.do"
			(at 33.02 45.72 0)
			(effects
				(font
					(size 1.27 1.27)
					(thickness 0.15)
				)
				(justify left bottom)
				(hide yes)
			)
		)
		(property "Description" "SMD Multilayer Ceramic Capacitor"
			(at 17.78 66.04 0)
			(effects
				(font
					(size 1.27 1.27)
				)
				(hide yes)
			)
		)
		(property "Manufacturer" "Samsung Electro-Mechanics"
			(at 38.1 45.72 0)
			(effects
				(font
					(size 1.27 1.27)
					(thickness 0.15)
				)
				(justify left bottom)
				(hide yes)
			)
		)
		(property "MPN" "CL10A226MO7JZNC"
			(at 35.56 45.72 0)
			(effects
				(font
					(size 1.27 1.27)
					(thickness 0.15)
				)
				(justify left bottom)
				(hide yes)
			)
		)
		(property "Val" "22u"
			(at 20.32 64.7636 90)
			(effects
				(font
					(size 1.27 1.27)
					(thickness 0.15)
				)
				(justify right)
			)
		)
		(property "License" "Apache-2.0"
			(at 40.64 45.72 0)
			(effects
				(font
					(size 1.27 1.27)
					(thickness 0.15)
				)
				(justify left bottom)
				(hide yes)
			)
		)
		(property "Author" "Antmicro"
			(at 43.18 45.72 0)
			(effects
				(font
					(size 1.27 1.27)
					(thickness 0.15)
				)
				(justify left bottom)
				(hide yes)
			)
		)
		(property "Voltage" "16V"
			(at 45.72 45.72 0)
			(effects
				(font
					(size 1.27 1.27)
				)
				(justify left bottom)
				(hide yes)
			)
		)
		(property "Dielectric" ""
			(at 48.26 45.72 0)
			(effects
				(font
					(size 1.27 1.27)
				)
				(justify left bottom)
				(hide yes)
			)
		)
		(pin "1"
		)
		(pin "2"
		)
		(instances
			(project "jetson-agx-thor-baseboard"
				(path ""
					(reference "C312")
					(unit 1)
				)
			)
		)
	)
	(symbol
		(lib_id "antmicroTransistorsFETsMOSFETsArrays:DMC2400UV-7")
		(at 165.1 241.3 180)
		(unit 1)
		(exclude_from_sim no)
		(in_bom yes)
		(on_board yes)
		(dnp no)
		(property "Reference" "Q21"
			(at 158.75 244.348 0)
			(effects
				(font
					(size 1.27 1.27)
					(thickness 0.15)
				)
			)
		)
		(property "Value" "DMC2400UV-7"
			(at 137.16 236.22 0)
			(effects
				(font
					(size 1.27 1.27)
					(thickness 0.15)
				)
				(justify left bottom)
				(hide yes)
			)
		)
		(property "Footprint" "antmicro-footprints:SOT-563"
			(at 137.16 233.68 0)
			(effects
				(font
					(size 1.27 1.27)
					(thickness 0.15)
				)
				(justify left bottom)
				(hide yes)
			)
		)
		(property "Datasheet" "https://www.mouser.com/datasheet/2/115/DIOD_S_A0010038249_1-2543538.pdf"
			(at 137.16 231.14 0)
			(effects
				(font
					(size 1.27 1.27)
					(thickness 0.15)
				)
				(justify left bottom)
				(hide yes)
			)
		)
		(property "Description" "Dual MOSFET, Complementary N and P Channel, 20 V, 20 V, 1.03 A, 1.03 A, 0.3 ohm"
			(at 137.16 218.44 0)
			(effects
				(font
					(size 1.27 1.27)
				)
				(justify left bottom)
				(hide yes)
			)
		)
		(property "MPN" "DMC2400UV-7"
			(at 158.75 246.888 0)
			(effects
				(font
					(size 1.27 1.27)
					(thickness 0.15)
				)
			)
		)
		(property "Manufacturer" "Diodes Incorporated"
			(at 137.16 226.06 0)
			(effects
				(font
					(size 1.27 1.27)
					(thickness 0.15)
				)
				(justify left bottom)
				(hide yes)
			)
		)
		(property "Author" "Antmicro"
			(at 137.16 223.52 0)
			(effects
				(font
					(size 1.27 1.27)
					(thickness 0.15)
				)
				(justify left bottom)
				(hide yes)
			)
		)
		(property "License" "Apache-2.0"
			(at 137.16 220.98 0)
			(effects
				(font
					(size 1.27 1.27)
					(thickness 0.15)
				)
				(justify left bottom)
				(hide yes)
			)
		)
		(pin "5"
		)
		(pin "3"
		)
		(pin "6"
		)
		(pin "2"
		)
		(pin "1"
		)
		(pin "4"
		)
		(instances
			(project "jetson-agx-thor-baseboard"
				(path ""
					(reference "Q21")
					(unit 1)
				)
			)
		)
	)
	(symbol
		(lib_id "antmicroCapacitors0402:C_100n_0402")
		(at 38.1 48.26 90)
		(unit 1)
		(exclude_from_sim no)
		(in_bom yes)
		(on_board yes)
		(dnp no)
		(property "Reference" "C86"
			(at 40.64 44.4436 90)
			(effects
				(font
					(size 1.27 1.27)
					(thickness 0.15)
				)
				(justify right)
			)
		)
		(property "Value" "C_100n_0402"
			(at 60.96 33.02 0)
			(effects
				(font
					(size 1.27 1.27)
					(thickness 0.15)
				)
				(justify left bottom)
				(hide yes)
			)
		)
		(property "Footprint" "antmicro-footprints:C_0402_1005Metric"
			(at 63.5 33.02 0)
			(effects
				(font
					(size 1.27 1.27)
					(thickness 0.15)
				)
				(justify left bottom)
				(hide yes)
			)
		)
		(property "Datasheet" "https://www.murata.com/products/productdetail?partno=GRM155R61H104KE14%23"
			(at 66.04 33.02 0)
			(effects
				(font
					(size 1.27 1.27)
					(thickness 0.15)
				)
				(justify left bottom)
				(hide yes)
			)
		)
		(property "Description" "SMD Multilayer Ceramic Capacitor, 0.1 µF, 50 V, 0402 [1005 Metric], ± 10%, X5R, GRM Series"
			(at 38.1 48.26 0)
			(effects
				(font
					(size 1.27 1.27)
				)
				(hide yes)
			)
		)
		(property "MPN" "GRM155R61H104KE14D"
			(at 68.58 33.02 0)
			(effects
				(font
					(size 1.27 1.27)
					(thickness 0.15)
				)
				(justify left bottom)
				(hide yes)
			)
		)
		(property "Val" "100n"
			(at 40.64 46.9836 90)
			(effects
				(font
					(size 1.27 1.27)
					(thickness 0.15)
				)
				(justify right)
			)
		)
		(property "Voltage" "50V"
			(at 48.26 33.02 0)
			(effects
				(font
					(size 1.27 1.27)
					(thickness 0.15)
				)
				(justify left bottom)
				(hide yes)
			)
		)
		(property "Dielectric" "X5R"
			(at 50.8 33.02 0)
			(effects
				(font
					(size 1.27 1.27)
					(thickness 0.15)
				)
				(justify left bottom)
				(hide yes)
			)
		)
		(property "Manufacturer" "Murata"
			(at 53.34 33.02 0)
			(effects
				(font
					(size 1.27 1.27)
					(thickness 0.15)
				)
				(justify left bottom)
				(hide yes)
			)
		)
		(property "License" "Apache-2.0"
			(at 55.88 33.02 0)
			(effects
				(font
					(size 1.27 1.27)
					(thickness 0.15)
				)
				(justify left bottom)
				(hide yes)
			)
		)
		(property "Author" "Antmicro"
			(at 58.42 33.02 0)
			(effects
				(font
					(size 1.27 1.27)
					(thickness 0.15)
				)
				(justify left bottom)
				(hide yes)
			)
		)
		(pin "1"
		)
		(pin "2"
		)
		(instances
			(project "jetson-agx-thor-baseboard"
				(path ""
					(reference "C86")
					(unit 1)
				)
			)
		)
	)
	(symbol
		(lib_id "antmicroResistors0402:R_49k9_0402")
		(at 27.94 135.89 90)
		(unit 1)
		(exclude_from_sim no)
		(in_bom yes)
		(on_board yes)
		(dnp no)
		(property "Reference" "R82"
			(at 29.464 133.096 90)
			(effects
				(font
					(size 1.27 1.27)
					(thickness 0.15)
				)
				(justify right)
			)
		)
		(property "Value" "R_49k9_0402"
			(at 40.64 115.57 0)
			(effects
				(font
					(size 1.27 1.27)
					(thickness 0.15)
				)
				(justify left bottom)
				(hide yes)
			)
		)
		(property "Footprint" "antmicro-footprints:R_0402_1005Metric"
			(at 43.18 115.57 0)
			(effects
				(font
					(size 1.27 1.27)
					(thickness 0.15)
				)
				(justify left bottom)
				(hide yes)
			)
		)
		(property "Datasheet" "https://www.bourns.com/docs/product-datasheets/cr.pdf"
			(at 45.72 115.57 0)
			(effects
				(font
					(size 1.27 1.27)
					(thickness 0.15)
				)
				(justify left bottom)
				(hide yes)
			)
		)
		(property "Description" "SMD Chip Resistor, 49.9 kohm, ± 1%, 63 mW, 0402 [1005 Metric], Thick Film, General Purpose"
			(at 27.94 135.89 0)
			(effects
				(font
					(size 1.27 1.27)
				)
				(hide yes)
			)
		)
		(property "MPN" "CR0402-FX-4992GLF"
			(at 48.26 115.57 0)
			(effects
				(font
					(size 1.27 1.27)
					(thickness 0.15)
				)
				(justify left bottom)
				(hide yes)
			)
		)
		(property "Manufacturer" "Bourns"
			(at 50.8 115.57 0)
			(effects
				(font
					(size 1.27 1.27)
					(thickness 0.15)
				)
				(justify left bottom)
				(hide yes)
			)
		)
		(property "License" "Apache-2.0"
			(at 53.34 115.57 0)
			(effects
				(font
					(size 1.27 1.27)
					(thickness 0.15)
				)
				(justify left bottom)
				(hide yes)
			)
		)
		(property "Author" "Antmicro"
			(at 55.88 115.57 0)
			(effects
				(font
					(size 1.27 1.27)
					(thickness 0.15)
				)
				(justify left bottom)
				(hide yes)
			)
		)
		(property "Val" "49k9"
			(at 29.464 135.636 90)
			(effects
				(font
					(size 1.27 1.27)
					(thickness 0.15)
				)
				(justify right)
			)
		)
		(property "Tolerance" "1%"
			(at 38.1 115.57 0)
			(effects
				(font
					(size 1.27 1.27)
				)
				(justify left bottom)
				(hide yes)
			)
		)
		(pin "1"
		)
		(pin "2"
		)
		(instances
			(project "jetson-agx-thor-baseboard"
				(path ""
					(reference "R82")
					(unit 1)
				)
			)
		)
	)
	(symbol
		(lib_id "antmicroResistors0402:R_100k_0402")
		(at 205.74 195.58 270)
		(mirror x)
		(unit 1)
		(exclude_from_sim no)
		(in_bom yes)
		(on_board yes)
		(dnp no)
		(property "Reference" "R239"
			(at 204.47 191.77 90)
			(effects
				(font
					(size 1.27 1.27)
					(thickness 0.15)
				)
				(justify right)
			)
		)
		(property "Value" "R_100k_0402"
			(at 193.04 175.26 0)
			(effects
				(font
					(size 1.27 1.27)
					(thickness 0.15)
				)
				(justify left bottom)
				(hide yes)
			)
		)
		(property "Footprint" "antmicro-footprints:R_0402_1005Metric"
			(at 190.5 175.26 0)
			(effects
				(font
					(size 1.27 1.27)
					(thickness 0.15)
				)
				(justify left bottom)
				(hide yes)
			)
		)
		(property "Datasheet" "https://www.bourns.com/docs/product-datasheets/cr.pdf"
			(at 187.96 175.26 0)
			(effects
				(font
					(size 1.27 1.27)
					(thickness 0.15)
				)
				(justify left bottom)
				(hide yes)
			)
		)
		(property "Description" "SMD Chip Resistor, 100 kohm, ± 1%, 62.5 mW, 0402 [1005 Metric], Thick Film, General Purpose"
			(at 175.26 175.26 0)
			(effects
				(font
					(size 1.27 1.27)
				)
				(justify left bottom)
				(hide yes)
			)
		)
		(property "MPN" "CR0402-FX-1003GLF"
			(at 185.42 175.26 0)
			(effects
				(font
					(size 1.27 1.27)
					(thickness 0.15)
				)
				(justify left bottom)
				(hide yes)
			)
		)
		(property "Manufacturer" "Bourns"
			(at 182.88 175.26 0)
			(effects
				(font
					(size 1.27 1.27)
					(thickness 0.15)
				)
				(justify left bottom)
				(hide yes)
			)
		)
		(property "License" "Apache-2.0"
			(at 180.34 175.26 0)
			(effects
				(font
					(size 1.27 1.27)
					(thickness 0.15)
				)
				(justify left bottom)
				(hide yes)
			)
		)
		(property "Author" "Antmicro"
			(at 177.8 175.26 0)
			(effects
				(font
					(size 1.27 1.27)
					(thickness 0.15)
				)
				(justify left bottom)
				(hide yes)
			)
		)
		(property "Val" "100k"
			(at 204.47 194.31 90)
			(effects
				(font
					(size 1.27 1.27)
					(thickness 0.15)
				)
				(justify right)
			)
		)
		(property "Tolerance" "1%"
			(at 195.58 175.26 0)
			(effects
				(font
					(size 1.27 1.27)
				)
				(justify left bottom)
				(hide yes)
			)
		)
		(pin "2"
		)
		(pin "1"
		)
		(instances
			(project "jetson-agx-thor-baseboard"
				(path ""
					(reference "R239")
					(unit 1)
				)
			)
		)
	)
	(symbol
		(lib_id "antmicroCapacitors0402:C_100n_0402")
		(at 96.52 80.01 0)
		(mirror x)
		(unit 1)
		(exclude_from_sim no)
		(in_bom yes)
		(on_board yes)
		(dnp no)
		(property "Reference" "C254"
			(at 105.41 78.74 0)
			(effects
				(font
					(size 1.27 1.27)
				)
			)
		)
		(property "Value" "C_100n_0402"
			(at 116.84 69.85 0)
			(effects
				(font
					(size 1.27 1.27)
					(thickness 0.15)
				)
				(justify left bottom)
				(hide yes)
			)
		)
		(property "Footprint" "antmicro-footprints:C_0402_1005Metric"
			(at 116.84 67.31 0)
			(effects
				(font
					(size 1.27 1.27)
					(thickness 0.15)
				)
				(justify left bottom)
				(hide yes)
			)
		)
		(property "Datasheet" "https://www.murata.com/products/productdetail?partno=GRM155R61H104KE14%23"
			(at 116.84 64.77 0)
			(effects
				(font
					(size 1.27 1.27)
					(thickness 0.15)
				)
				(justify left bottom)
				(hide yes)
			)
		)
		(property "Description" "SMD Multilayer Ceramic Capacitor, 0.1 µF, 50 V, 0402 [1005 Metric], ± 10%, X5R, GRM Series"
			(at 96.52 80.01 0)
			(effects
				(font
					(size 1.27 1.27)
				)
				(hide yes)
			)
		)
		(property "Manufacturer" "Murata"
			(at 116.84 59.69 0)
			(effects
				(font
					(size 1.27 1.27)
					(thickness 0.15)
				)
				(justify left bottom)
				(hide yes)
			)
		)
		(property "MPN" "GRM155R61H104KE14D"
			(at 116.84 62.23 0)
			(effects
				(font
					(size 1.27 1.27)
					(thickness 0.15)
				)
				(justify left bottom)
				(hide yes)
			)
		)
		(property "Val" "100n"
			(at 95.758 78.994 0)
			(effects
				(font
					(size 1.27 1.27)
					(thickness 0.15)
				)
			)
		)
		(property "License" "Apache-2.0"
			(at 116.84 57.15 0)
			(effects
				(font
					(size 1.27 1.27)
					(thickness 0.15)
				)
				(justify left bottom)
				(hide yes)
			)
		)
		(property "Author" "Antmicro"
			(at 116.84 54.61 0)
			(effects
				(font
					(size 1.27 1.27)
					(thickness 0.15)
				)
				(justify left bottom)
				(hide yes)
			)
		)
		(property "Voltage" "50V"
			(at 116.84 52.07 0)
			(effects
				(font
					(size 1.27 1.27)
				)
				(justify left bottom)
				(hide yes)
			)
		)
		(property "Dielectric" "X5R"
			(at 116.84 49.53 0)
			(effects
				(font
					(size 1.27 1.27)
				)
				(justify left bottom)
				(hide yes)
			)
		)
		(pin "1"
		)
		(pin "2"
		)
		(instances
			(project "jetson-agx-thor-baseboard"
				(path ""
					(reference "C254")
					(unit 1)
				)
			)
		)
	)
	(symbol
		(lib_id "antmicroResistors0402:R_10k_0402")
		(at 207.01 232.41 90)
		(mirror x)
		(unit 1)
		(exclude_from_sim no)
		(in_bom yes)
		(on_board yes)
		(dnp no)
		(property "Reference" "R332"
			(at 200.66 233.68 90)
			(effects
				(font
					(size 1.27 1.27)
					(thickness 0.15)
				)
				(justify right)
			)
		)
		(property "Value" "R_10k_0402"
			(at 219.71 252.73 0)
			(effects
				(font
					(size 1.27 1.27)
					(thickness 0.15)
				)
				(justify left bottom)
				(hide yes)
			)
		)
		(property "Footprint" "antmicro-footprints:R_0402_1005Metric"
			(at 222.25 252.73 0)
			(effects
				(font
					(size 1.27 1.27)
					(thickness 0.15)
				)
				(justify left bottom)
				(hide yes)
			)
		)
		(property "Datasheet" "https://www.bourns.com/docs/product-datasheets/cr.pdf"
			(at 224.79 252.73 0)
			(effects
				(font
					(size 1.27 1.27)
					(thickness 0.15)
				)
				(justify left bottom)
				(hide yes)
			)
		)
		(property "Description" "SMD Chip Resistor, 10 kohm, ± 1%, 62.5 mW, 0402 [1005 Metric], Thick Film, General Purpose"
			(at 207.01 232.41 0)
			(effects
				(font
					(size 1.27 1.27)
				)
				(hide yes)
			)
		)
		(property "MPN" "CR0402-FX-1002GLF"
			(at 227.33 252.73 0)
			(effects
				(font
					(size 1.27 1.27)
					(thickness 0.15)
				)
				(justify left bottom)
				(hide yes)
			)
		)
		(property "Manufacturer" "Bourns"
			(at 229.87 252.73 0)
			(effects
				(font
					(size 1.27 1.27)
					(thickness 0.15)
				)
				(justify left bottom)
				(hide yes)
			)
		)
		(property "License" "Apache-2.0"
			(at 232.41 252.73 0)
			(effects
				(font
					(size 1.27 1.27)
					(thickness 0.15)
				)
				(justify left bottom)
				(hide yes)
			)
		)
		(property "Author" "Antmicro"
			(at 234.95 252.73 0)
			(effects
				(font
					(size 1.27 1.27)
					(thickness 0.15)
				)
				(justify left bottom)
				(hide yes)
			)
		)
		(property "Val" "10k"
			(at 201.93 236.22 90)
			(effects
				(font
					(size 1.27 1.27)
					(thickness 0.15)
				)
				(justify right)
			)
		)
		(property "Tolerance" "1%"
			(at 217.17 252.73 0)
			(effects
				(font
					(size 1.27 1.27)
				)
				(justify left bottom)
				(hide yes)
			)
		)
		(pin "2"
		)
		(pin "1"
		)
		(instances
			(project "jetson-agx-thor-baseboard"
				(path ""
					(reference "R332")
					(unit 1)
				)
			)
		)
	)
	(symbol
		(lib_id "antmicroResistors0402:R_49k9_0402")
		(at 208.28 69.85 90)
		(unit 1)
		(exclude_from_sim no)
		(in_bom yes)
		(on_board yes)
		(dnp no)
		(property "Reference" "R92"
			(at 209.804 67.056 90)
			(effects
				(font
					(size 1.27 1.27)
					(thickness 0.15)
				)
				(justify right)
			)
		)
		(property "Value" "R_49k9_0402"
			(at 220.98 49.53 0)
			(effects
				(font
					(size 1.27 1.27)
					(thickness 0.15)
				)
				(justify left bottom)
				(hide yes)
			)
		)
		(property "Footprint" "antmicro-footprints:R_0402_1005Metric"
			(at 223.52 49.53 0)
			(effects
				(font
					(size 1.27 1.27)
					(thickness 0.15)
				)
				(justify left bottom)
				(hide yes)
			)
		)
		(property "Datasheet" "https://www.bourns.com/docs/product-datasheets/cr.pdf"
			(at 226.06 49.53 0)
			(effects
				(font
					(size 1.27 1.27)
					(thickness 0.15)
				)
				(justify left bottom)
				(hide yes)
			)
		)
		(property "Description" "SMD Chip Resistor, 49.9 kohm, ± 1%, 63 mW, 0402 [1005 Metric], Thick Film, General Purpose"
			(at 208.28 69.85 0)
			(effects
				(font
					(size 1.27 1.27)
				)
				(hide yes)
			)
		)
		(property "MPN" "CR0402-FX-4992GLF"
			(at 228.6 49.53 0)
			(effects
				(font
					(size 1.27 1.27)
					(thickness 0.15)
				)
				(justify left bottom)
				(hide yes)
			)
		)
		(property "Manufacturer" "Bourns"
			(at 231.14 49.53 0)
			(effects
				(font
					(size 1.27 1.27)
					(thickness 0.15)
				)
				(justify left bottom)
				(hide yes)
			)
		)
		(property "License" "Apache-2.0"
			(at 233.68 49.53 0)
			(effects
				(font
					(size 1.27 1.27)
					(thickness 0.15)
				)
				(justify left bottom)
				(hide yes)
			)
		)
		(property "Author" "Antmicro"
			(at 236.22 49.53 0)
			(effects
				(font
					(size 1.27 1.27)
					(thickness 0.15)
				)
				(justify left bottom)
				(hide yes)
			)
		)
		(property "Val" "49k9"
			(at 209.804 69.596 90)
			(effects
				(font
					(size 1.27 1.27)
					(thickness 0.15)
				)
				(justify right)
			)
		)
		(property "Tolerance" "1%"
			(at 218.44 49.53 0)
			(effects
				(font
					(size 1.27 1.27)
				)
				(justify left bottom)
				(hide yes)
			)
		)
		(pin "1"
		)
		(pin "2"
		)
		(instances
			(project ""
				(path ""
					(reference "R92")
					(unit 1)
				)
			)
		)
	)
	(symbol
		(lib_id "antmicroCapacitors0402:C_100n_0402")
		(at 38.1 66.04 90)
		(unit 1)
		(exclude_from_sim no)
		(in_bom yes)
		(on_board yes)
		(dnp no)
		(property "Reference" "C47"
			(at 40.64 62.2236 90)
			(effects
				(font
					(size 1.27 1.27)
					(thickness 0.15)
				)
				(justify right)
			)
		)
		(property "Value" "C_100n_0402"
			(at 60.96 50.8 0)
			(effects
				(font
					(size 1.27 1.27)
					(thickness 0.15)
				)
				(justify left bottom)
				(hide yes)
			)
		)
		(property "Footprint" "antmicro-footprints:C_0402_1005Metric"
			(at 63.5 50.8 0)
			(effects
				(font
					(size 1.27 1.27)
					(thickness 0.15)
				)
				(justify left bottom)
				(hide yes)
			)
		)
		(property "Datasheet" "https://www.murata.com/products/productdetail?partno=GRM155R61H104KE14%23"
			(at 66.04 50.8 0)
			(effects
				(font
					(size 1.27 1.27)
					(thickness 0.15)
				)
				(justify left bottom)
				(hide yes)
			)
		)
		(property "Description" "SMD Multilayer Ceramic Capacitor, 0.1 µF, 50 V, 0402 [1005 Metric], ± 10%, X5R, GRM Series"
			(at 38.1 66.04 0)
			(effects
				(font
					(size 1.27 1.27)
				)
				(hide yes)
			)
		)
		(property "MPN" "GRM155R61H104KE14D"
			(at 68.58 50.8 0)
			(effects
				(font
					(size 1.27 1.27)
					(thickness 0.15)
				)
				(justify left bottom)
				(hide yes)
			)
		)
		(property "Val" "100n"
			(at 40.64 64.7636 90)
			(effects
				(font
					(size 1.27 1.27)
					(thickness 0.15)
				)
				(justify right)
			)
		)
		(property "Voltage" "50V"
			(at 48.26 50.8 0)
			(effects
				(font
					(size 1.27 1.27)
					(thickness 0.15)
				)
				(justify left bottom)
				(hide yes)
			)
		)
		(property "Dielectric" "X5R"
			(at 50.8 50.8 0)
			(effects
				(font
					(size 1.27 1.27)
					(thickness 0.15)
				)
				(justify left bottom)
				(hide yes)
			)
		)
		(property "Manufacturer" "Murata"
			(at 53.34 50.8 0)
			(effects
				(font
					(size 1.27 1.27)
					(thickness 0.15)
				)
				(justify left bottom)
				(hide yes)
			)
		)
		(property "License" "Apache-2.0"
			(at 55.88 50.8 0)
			(effects
				(font
					(size 1.27 1.27)
					(thickness 0.15)
				)
				(justify left bottom)
				(hide yes)
			)
		)
		(property "Author" "Antmicro"
			(at 58.42 50.8 0)
			(effects
				(font
					(size 1.27 1.27)
					(thickness 0.15)
				)
				(justify left bottom)
				(hide yes)
			)
		)
		(pin "1"
		)
		(pin "2"
		)
		(instances
			(project "jetson-agx-thor-baseboard"
				(path ""
					(reference "C47")
					(unit 1)
				)
			)
		)
	)
	(symbol
		(lib_id "antmicroResistors0402:R_0R_0402")
		(at 52.07 256.54 0)
		(unit 1)
		(exclude_from_sim no)
		(in_bom no)
		(on_board yes)
		(dnp yes)
		(property "Reference" "R380"
			(at 50.038 255.778 0)
			(effects
				(font
					(size 1.27 1.27)
					(thickness 0.15)
				)
			)
		)
		(property "Value" "R_0R_0402"
			(at 72.39 269.24 0)
			(effects
				(font
					(size 1.27 1.27)
					(thickness 0.15)
				)
				(justify left bottom)
				(hide yes)
			)
		)
		(property "Footprint" "antmicro-footprints:R_0402_1005Metric"
			(at 72.39 271.78 0)
			(effects
				(font
					(size 1.27 1.27)
					(thickness 0.15)
				)
				(justify left bottom)
				(hide yes)
			)
		)
		(property "Datasheet" "https://industrial.panasonic.com/cdbs/www-data/pdf/RDA0000/AOA0000C301.pdf"
			(at 72.39 274.32 0)
			(effects
				(font
					(size 1.27 1.27)
					(thickness 0.15)
				)
				(justify left bottom)
				(hide yes)
			)
		)
		(property "Description" "SMD Chip Resistor, Jumper, 0 ohm, 100 mW, 0402 [1005 Metric], Thick Film, General Purpose"
			(at 72.39 289.56 0)
			(effects
				(font
					(size 1.27 1.27)
				)
				(justify left bottom)
				(hide yes)
			)
		)
		(property "MPN" "ERJ2GE0R00X"
			(at 72.39 276.86 0)
			(effects
				(font
					(size 1.27 1.27)
					(thickness 0.15)
				)
				(justify left bottom)
				(hide yes)
			)
		)
		(property "Manufacturer" "Panasonic"
			(at 72.39 279.4 0)
			(effects
				(font
					(size 1.27 1.27)
					(thickness 0.15)
				)
				(justify left bottom)
				(hide yes)
			)
		)
		(property "License" "Apache-2.0"
			(at 72.39 281.94 0)
			(effects
				(font
					(size 1.27 1.27)
					(thickness 0.15)
				)
				(justify left bottom)
				(hide yes)
			)
		)
		(property "Author" "Antmicro"
			(at 72.39 284.48 0)
			(effects
				(font
					(size 1.27 1.27)
					(thickness 0.15)
				)
				(justify left bottom)
				(hide yes)
			)
		)
		(property "Val" "0R"
			(at 58.42 255.778 0)
			(effects
				(font
					(size 1.27 1.27)
					(thickness 0.15)
				)
			)
		)
		(property "Tolerance" "~"
			(at 72.39 266.7 0)
			(effects
				(font
					(size 1.27 1.27)
				)
				(justify left bottom)
				(hide yes)
			)
		)
		(property "Current" "1A"
			(at 72.39 287.02 0)
			(effects
				(font
					(size 1.27 1.27)
					(thickness 0.15)
				)
				(justify left bottom)
				(hide yes)
			)
		)
		(pin "1"
		)
		(pin "2"
		)
		(instances
			(project "jetson-agx-thor-baseboard"
				(path ""
					(reference "R380")
					(unit 1)
				)
			)
		)
	)
	(symbol
		(lib_id "antmicropower:GND")
		(at 27.94 102.87 0)
		(mirror y)
		(unit 1)
		(exclude_from_sim no)
		(in_bom yes)
		(on_board yes)
		(dnp no)
		(property "Reference" "#PWR0181"
			(at 27.94 109.22 0)
			(effects
				(font
					(size 1.27 1.27)
				)
				(justify left bottom)
				(hide yes)
			)
		)
		(property "Value" "GND"
			(at 27.94 106.68 0)
			(effects
				(font
					(size 1.27 1.27)
					(thickness 0.15)
				)
			)
		)
		(property "Footprint" ""
			(at 19.05 110.49 0)
			(effects
				(font
					(size 1.27 1.27)
					(thickness 0.15)
				)
				(justify left bottom)
				(hide yes)
			)
		)
		(property "Datasheet" ""
			(at 19.05 115.57 0)
			(effects
				(font
					(size 1.27 1.27)
					(thickness 0.15)
				)
				(justify left bottom)
				(hide yes)
			)
		)
		(property "Description" ""
			(at 27.94 102.87 0)
			(effects
				(font
					(size 1.27 1.27)
				)
				(hide yes)
			)
		)
		(property "Author" "Antmicro"
			(at 19.05 110.49 0)
			(effects
				(font
					(size 1.27 1.27)
					(thickness 0.15)
				)
				(justify left bottom)
				(hide yes)
			)
		)
		(property "License" "Apache-2.0"
			(at 19.05 113.03 0)
			(effects
				(font
					(size 1.27 1.27)
					(thickness 0.15)
				)
				(justify left bottom)
				(hide yes)
			)
		)
		(pin "1"
		)
		(instances
			(project "jetson-agx-thor-baseboard"
				(path ""
					(reference "#PWR0181")
					(unit 1)
				)
			)
		)
	)
	(symbol
		(lib_id "antmicroResistors0402:R_0R_0402")
		(at 187.96 158.75 0)
		(unit 1)
		(exclude_from_sim no)
		(in_bom yes)
		(on_board yes)
		(dnp no)
		(property "Reference" "R48"
			(at 193.04 158.115 0)
			(effects
				(font
					(size 1.27 1.27)
				)
				(justify left bottom)
			)
		)
		(property "Value" "R_0R_0402"
			(at 208.28 171.45 0)
			(effects
				(font
					(size 1.27 1.27)
					(thickness 0.15)
				)
				(justify left bottom)
				(hide yes)
			)
		)
		(property "Footprint" "antmicro-footprints:R_0402_1005Metric"
			(at 208.28 173.99 0)
			(effects
				(font
					(size 1.27 1.27)
					(thickness 0.15)
				)
				(justify left bottom)
				(hide yes)
			)
		)
		(property "Datasheet" "https://industrial.panasonic.com/cdbs/www-data/pdf/RDA0000/AOA0000C301.pdf"
			(at 208.28 176.53 0)
			(effects
				(font
					(size 1.27 1.27)
					(thickness 0.15)
				)
				(justify left bottom)
				(hide yes)
			)
		)
		(property "Description" "SMD Chip Resistor, Jumper, 0 ohm, 100 mW, 0402 [1005 Metric], Thick Film, General Purpose"
			(at 187.96 158.75 0)
			(effects
				(font
					(size 1.27 1.27)
				)
				(hide yes)
			)
		)
		(property "Manufacturer" "Panasonic"
			(at 208.28 181.61 0)
			(effects
				(font
					(size 1.27 1.27)
					(thickness 0.15)
				)
				(justify left bottom)
				(hide yes)
			)
		)
		(property "MPN" "ERJ2GE0R00X"
			(at 208.28 179.07 0)
			(effects
				(font
					(size 1.27 1.27)
					(thickness 0.15)
				)
				(justify left bottom)
				(hide yes)
			)
		)
		(property "Val" "0R"
			(at 185.42 158.115 0)
			(effects
				(font
					(size 1.27 1.27)
					(thickness 0.15)
				)
				(justify left bottom)
			)
		)
		(property "License" "Apache-2.0"
			(at 208.28 184.15 0)
			(effects
				(font
					(size 1.27 1.27)
					(thickness 0.15)
				)
				(justify left bottom)
				(hide yes)
			)
		)
		(property "Author" "Antmicro"
			(at 208.28 186.69 0)
			(effects
				(font
					(size 1.27 1.27)
					(thickness 0.15)
				)
				(justify left bottom)
				(hide yes)
			)
		)
		(property "Tolerance" "~"
			(at 208.28 168.91 0)
			(effects
				(font
					(size 1.27 1.27)
				)
				(justify left bottom)
				(hide yes)
			)
		)
		(property "Current" "1A"
			(at 208.28 189.23 0)
			(effects
				(font
					(size 1.27 1.27)
					(thickness 0.15)
				)
				(justify left bottom)
				(hide yes)
			)
		)
		(pin "1"
		)
		(pin "2"
		)
		(instances
			(project "jetson-agx-thor-baseboard"
				(path ""
					(reference "R48")
					(unit 1)
				)
			)
		)
	)
	(symbol
		(lib_id "antmicroResistors0402:R_0R_0402")
		(at 52.07 248.92 0)
		(unit 1)
		(exclude_from_sim no)
		(in_bom no)
		(on_board yes)
		(dnp yes)
		(property "Reference" "R88"
			(at 50.038 248.158 0)
			(effects
				(font
					(size 1.27 1.27)
					(thickness 0.15)
				)
			)
		)
		(property "Value" "R_0R_0402"
			(at 72.39 261.62 0)
			(effects
				(font
					(size 1.27 1.27)
					(thickness 0.15)
				)
				(justify left bottom)
				(hide yes)
			)
		)
		(property "Footprint" "antmicro-footprints:R_0402_1005Metric"
			(at 72.39 264.16 0)
			(effects
				(font
					(size 1.27 1.27)
					(thickness 0.15)
				)
				(justify left bottom)
				(hide yes)
			)
		)
		(property "Datasheet" "https://industrial.panasonic.com/cdbs/www-data/pdf/RDA0000/AOA0000C301.pdf"
			(at 72.39 266.7 0)
			(effects
				(font
					(size 1.27 1.27)
					(thickness 0.15)
				)
				(justify left bottom)
				(hide yes)
			)
		)
		(property "Description" "SMD Chip Resistor, Jumper, 0 ohm, 100 mW, 0402 [1005 Metric], Thick Film, General Purpose"
			(at 72.39 281.94 0)
			(effects
				(font
					(size 1.27 1.27)
				)
				(justify left bottom)
				(hide yes)
			)
		)
		(property "MPN" "ERJ2GE0R00X"
			(at 72.39 269.24 0)
			(effects
				(font
					(size 1.27 1.27)
					(thickness 0.15)
				)
				(justify left bottom)
				(hide yes)
			)
		)
		(property "Manufacturer" "Panasonic"
			(at 72.39 271.78 0)
			(effects
				(font
					(size 1.27 1.27)
					(thickness 0.15)
				)
				(justify left bottom)
				(hide yes)
			)
		)
		(property "License" "Apache-2.0"
			(at 72.39 274.32 0)
			(effects
				(font
					(size 1.27 1.27)
					(thickness 0.15)
				)
				(justify left bottom)
				(hide yes)
			)
		)
		(property "Author" "Antmicro"
			(at 72.39 276.86 0)
			(effects
				(font
					(size 1.27 1.27)
					(thickness 0.15)
				)
				(justify left bottom)
				(hide yes)
			)
		)
		(property "Val" "0R"
			(at 58.42 248.158 0)
			(effects
				(font
					(size 1.27 1.27)
					(thickness 0.15)
				)
			)
		)
		(property "Tolerance" "~"
			(at 72.39 259.08 0)
			(effects
				(font
					(size 1.27 1.27)
				)
				(justify left bottom)
				(hide yes)
			)
		)
		(property "Current" "1A"
			(at 72.39 279.4 0)
			(effects
				(font
					(size 1.27 1.27)
					(thickness 0.15)
				)
				(justify left bottom)
				(hide yes)
			)
		)
		(pin "1"
		)
		(pin "2"
		)
		(instances
			(project ""
				(path ""
					(reference "R88")
					(unit 1)
				)
			)
		)
	)
	(symbol
		(lib_id "antmicropower:GND")
		(at 198.12 196.85 0)
		(unit 1)
		(exclude_from_sim no)
		(in_bom yes)
		(on_board yes)
		(dnp no)
		(property "Reference" "#PWR0630"
			(at 198.12 203.2 0)
			(effects
				(font
					(size 1.27 1.27)
				)
				(justify left bottom)
				(hide yes)
			)
		)
		(property "Value" "GND"
			(at 198.12 200.66 0)
			(effects
				(font
					(size 1.27 1.27)
					(thickness 0.15)
				)
			)
		)
		(property "Footprint" ""
			(at 207.01 204.47 0)
			(effects
				(font
					(size 1.27 1.27)
					(thickness 0.15)
				)
				(justify left bottom)
				(hide yes)
			)
		)
		(property "Datasheet" ""
			(at 207.01 209.55 0)
			(effects
				(font
					(size 1.27 1.27)
					(thickness 0.15)
				)
				(justify left bottom)
				(hide yes)
			)
		)
		(property "Description" ""
			(at 198.12 196.85 0)
			(effects
				(font
					(size 1.27 1.27)
				)
				(hide yes)
			)
		)
		(property "Author" "Antmicro"
			(at 207.01 204.47 0)
			(effects
				(font
					(size 1.27 1.27)
					(thickness 0.15)
				)
				(justify left bottom)
				(hide yes)
			)
		)
		(property "License" "Apache-2.0"
			(at 207.01 207.01 0)
			(effects
				(font
					(size 1.27 1.27)
					(thickness 0.15)
				)
				(justify left bottom)
				(hide yes)
			)
		)
		(pin "1"
		)
		(instances
			(project "jetson-agx-thor-baseboard"
				(path ""
					(reference "#PWR0630")
					(unit 1)
				)
			)
		)
	)
	(symbol
		(lib_id "antmicroResistors0402:R_0R_0402")
		(at 187.96 148.59 0)
		(unit 1)
		(exclude_from_sim no)
		(in_bom yes)
		(on_board yes)
		(dnp no)
		(property "Reference" "R21"
			(at 193.04 147.955 0)
			(effects
				(font
					(size 1.27 1.27)
				)
				(justify left bottom)
			)
		)
		(property "Value" "R_0R_0402"
			(at 208.28 161.29 0)
			(effects
				(font
					(size 1.27 1.27)
					(thickness 0.15)
				)
				(justify left bottom)
				(hide yes)
			)
		)
		(property "Footprint" "antmicro-footprints:R_0402_1005Metric"
			(at 208.28 163.83 0)
			(effects
				(font
					(size 1.27 1.27)
					(thickness 0.15)
				)
				(justify left bottom)
				(hide yes)
			)
		)
		(property "Datasheet" "https://industrial.panasonic.com/cdbs/www-data/pdf/RDA0000/AOA0000C301.pdf"
			(at 208.28 166.37 0)
			(effects
				(font
					(size 1.27 1.27)
					(thickness 0.15)
				)
				(justify left bottom)
				(hide yes)
			)
		)
		(property "Description" "SMD Chip Resistor, Jumper, 0 ohm, 100 mW, 0402 [1005 Metric], Thick Film, General Purpose"
			(at 187.96 148.59 0)
			(effects
				(font
					(size 1.27 1.27)
				)
				(hide yes)
			)
		)
		(property "Manufacturer" "Panasonic"
			(at 208.28 171.45 0)
			(effects
				(font
					(size 1.27 1.27)
					(thickness 0.15)
				)
				(justify left bottom)
				(hide yes)
			)
		)
		(property "MPN" "ERJ2GE0R00X"
			(at 208.28 168.91 0)
			(effects
				(font
					(size 1.27 1.27)
					(thickness 0.15)
				)
				(justify left bottom)
				(hide yes)
			)
		)
		(property "Val" "0R"
			(at 185.42 147.955 0)
			(effects
				(font
					(size 1.27 1.27)
					(thickness 0.15)
				)
				(justify left bottom)
			)
		)
		(property "License" "Apache-2.0"
			(at 208.28 173.99 0)
			(effects
				(font
					(size 1.27 1.27)
					(thickness 0.15)
				)
				(justify left bottom)
				(hide yes)
			)
		)
		(property "Author" "Antmicro"
			(at 208.28 176.53 0)
			(effects
				(font
					(size 1.27 1.27)
					(thickness 0.15)
				)
				(justify left bottom)
				(hide yes)
			)
		)
		(property "Tolerance" "~"
			(at 208.28 158.75 0)
			(effects
				(font
					(size 1.27 1.27)
				)
				(justify left bottom)
				(hide yes)
			)
		)
		(property "Current" "1A"
			(at 208.28 179.07 0)
			(effects
				(font
					(size 1.27 1.27)
					(thickness 0.15)
				)
				(justify left bottom)
				(hide yes)
			)
		)
		(pin "1"
		)
		(pin "2"
		)
		(instances
			(project "jetson-agx-thor-baseboard"
				(path ""
					(reference "R21")
					(unit 1)
				)
			)
		)
	)
	(symbol
		(lib_id "antmicropower:GND")
		(at 327.66 236.22 0)
		(unit 1)
		(exclude_from_sim no)
		(in_bom yes)
		(on_board yes)
		(dnp no)
		(property "Reference" "#PWR0180"
			(at 327.66 242.57 0)
			(effects
				(font
					(size 1.27 1.27)
				)
				(justify left bottom)
				(hide yes)
			)
		)
		(property "Value" "GND"
			(at 327.66 240.03 0)
			(effects
				(font
					(size 1.27 1.27)
					(thickness 0.15)
				)
			)
		)
		(property "Footprint" ""
			(at 336.55 243.84 0)
			(effects
				(font
					(size 1.27 1.27)
					(thickness 0.15)
				)
				(justify left bottom)
				(hide yes)
			)
		)
		(property "Datasheet" ""
			(at 336.55 248.92 0)
			(effects
				(font
					(size 1.27 1.27)
					(thickness 0.15)
				)
				(justify left bottom)
				(hide yes)
			)
		)
		(property "Description" ""
			(at 327.66 236.22 0)
			(effects
				(font
					(size 1.27 1.27)
				)
				(hide yes)
			)
		)
		(property "Author" "Antmicro"
			(at 336.55 243.84 0)
			(effects
				(font
					(size 1.27 1.27)
					(thickness 0.15)
				)
				(justify left bottom)
				(hide yes)
			)
		)
		(property "License" "Apache-2.0"
			(at 336.55 246.38 0)
			(effects
				(font
					(size 1.27 1.27)
					(thickness 0.15)
				)
				(justify left bottom)
				(hide yes)
			)
		)
		(pin "1"
		)
		(instances
			(project "jetson-agx-thor-baseboard"
				(path ""
					(reference "#PWR0180")
					(unit 1)
				)
			)
		)
	)
	(symbol
		(lib_id "antmicroCapacitors0402:C_100n_0402")
		(at 58.42 48.26 90)
		(unit 1)
		(exclude_from_sim no)
		(in_bom yes)
		(on_board yes)
		(dnp no)
		(fields_autoplaced yes)
		(property "Reference" "C90"
			(at 60.96 44.4436 90)
			(effects
				(font
					(size 1.27 1.27)
					(thickness 0.15)
				)
				(justify right)
			)
		)
		(property "Value" "C_100n_0402"
			(at 81.28 33.02 0)
			(effects
				(font
					(size 1.27 1.27)
					(thickness 0.15)
				)
				(justify left bottom)
				(hide yes)
			)
		)
		(property "Footprint" "antmicro-footprints:C_0402_1005Metric"
			(at 83.82 33.02 0)
			(effects
				(font
					(size 1.27 1.27)
					(thickness 0.15)
				)
				(justify left bottom)
				(hide yes)
			)
		)
		(property "Datasheet" "https://www.murata.com/products/productdetail?partno=GRM155R61H104KE14%23"
			(at 86.36 33.02 0)
			(effects
				(font
					(size 1.27 1.27)
					(thickness 0.15)
				)
				(justify left bottom)
				(hide yes)
			)
		)
		(property "Description" "SMD Multilayer Ceramic Capacitor, 0.1 µF, 50 V, 0402 [1005 Metric], ± 10%, X5R, GRM Series"
			(at 58.42 48.26 0)
			(effects
				(font
					(size 1.27 1.27)
				)
				(hide yes)
			)
		)
		(property "MPN" "GRM155R61H104KE14D"
			(at 88.9 33.02 0)
			(effects
				(font
					(size 1.27 1.27)
					(thickness 0.15)
				)
				(justify left bottom)
				(hide yes)
			)
		)
		(property "Val" "100n"
			(at 60.96 46.9836 90)
			(effects
				(font
					(size 1.27 1.27)
					(thickness 0.15)
				)
				(justify right)
			)
		)
		(property "Voltage" "50V"
			(at 68.58 33.02 0)
			(effects
				(font
					(size 1.27 1.27)
					(thickness 0.15)
				)
				(justify left bottom)
				(hide yes)
			)
		)
		(property "Dielectric" "X5R"
			(at 71.12 33.02 0)
			(effects
				(font
					(size 1.27 1.27)
					(thickness 0.15)
				)
				(justify left bottom)
				(hide yes)
			)
		)
		(property "Manufacturer" "Murata"
			(at 73.66 33.02 0)
			(effects
				(font
					(size 1.27 1.27)
					(thickness 0.15)
				)
				(justify left bottom)
				(hide yes)
			)
		)
		(property "License" "Apache-2.0"
			(at 76.2 33.02 0)
			(effects
				(font
					(size 1.27 1.27)
					(thickness 0.15)
				)
				(justify left bottom)
				(hide yes)
			)
		)
		(property "Author" "Antmicro"
			(at 78.74 33.02 0)
			(effects
				(font
					(size 1.27 1.27)
					(thickness 0.15)
				)
				(justify left bottom)
				(hide yes)
			)
		)
		(pin "1"
		)
		(pin "2"
		)
		(instances
			(project "jetson-agx-thor-baseboard"
				(path ""
					(reference "C90")
					(unit 1)
				)
			)
		)
	)
	(symbol
		(lib_id "antmicroCapacitors0402:C_100n_0402")
		(at 29.21 48.26 90)
		(unit 1)
		(exclude_from_sim no)
		(in_bom yes)
		(on_board yes)
		(dnp no)
		(property "Reference" "C358"
			(at 31.75 44.4436 90)
			(effects
				(font
					(size 1.27 1.27)
					(thickness 0.15)
				)
				(justify right)
			)
		)
		(property "Value" "C_100n_0402"
			(at 52.07 33.02 0)
			(effects
				(font
					(size 1.27 1.27)
					(thickness 0.15)
				)
				(justify left bottom)
				(hide yes)
			)
		)
		(property "Footprint" "antmicro-footprints:C_0402_1005Metric"
			(at 54.61 33.02 0)
			(effects
				(font
					(size 1.27 1.27)
					(thickness 0.15)
				)
				(justify left bottom)
				(hide yes)
			)
		)
		(property "Datasheet" "https://www.murata.com/products/productdetail?partno=GRM155R61H104KE14%23"
			(at 57.15 33.02 0)
			(effects
				(font
					(size 1.27 1.27)
					(thickness 0.15)
				)
				(justify left bottom)
				(hide yes)
			)
		)
		(property "Description" "SMD Multilayer Ceramic Capacitor, 0.1 µF, 50 V, 0402 [1005 Metric], ± 10%, X5R, GRM Series"
			(at 29.21 48.26 0)
			(effects
				(font
					(size 1.27 1.27)
				)
				(hide yes)
			)
		)
		(property "MPN" "GRM155R61H104KE14D"
			(at 59.69 33.02 0)
			(effects
				(font
					(size 1.27 1.27)
					(thickness 0.15)
				)
				(justify left bottom)
				(hide yes)
			)
		)
		(property "Val" "100n"
			(at 31.75 46.9836 90)
			(effects
				(font
					(size 1.27 1.27)
					(thickness 0.15)
				)
				(justify right)
			)
		)
		(property "Voltage" "50V"
			(at 39.37 33.02 0)
			(effects
				(font
					(size 1.27 1.27)
					(thickness 0.15)
				)
				(justify left bottom)
				(hide yes)
			)
		)
		(property "Dielectric" "X5R"
			(at 41.91 33.02 0)
			(effects
				(font
					(size 1.27 1.27)
					(thickness 0.15)
				)
				(justify left bottom)
				(hide yes)
			)
		)
		(property "Manufacturer" "Murata"
			(at 44.45 33.02 0)
			(effects
				(font
					(size 1.27 1.27)
					(thickness 0.15)
				)
				(justify left bottom)
				(hide yes)
			)
		)
		(property "License" "Apache-2.0"
			(at 46.99 33.02 0)
			(effects
				(font
					(size 1.27 1.27)
					(thickness 0.15)
				)
				(justify left bottom)
				(hide yes)
			)
		)
		(property "Author" "Antmicro"
			(at 49.53 33.02 0)
			(effects
				(font
					(size 1.27 1.27)
					(thickness 0.15)
				)
				(justify left bottom)
				(hide yes)
			)
		)
		(pin "1"
		)
		(pin "2"
		)
		(instances
			(project "jetson-agx-thor-baseboard"
				(path ""
					(reference "C358")
					(unit 1)
				)
			)
		)
	)
	(symbol
		(lib_id "antmicroResistors0402:R_10k_0402")
		(at 226.06 236.22 270)
		(unit 1)
		(exclude_from_sim no)
		(in_bom yes)
		(on_board yes)
		(dnp no)
		(property "Reference" "R334"
			(at 232.41 237.49 90)
			(effects
				(font
					(size 1.27 1.27)
					(thickness 0.15)
				)
				(justify right)
			)
		)
		(property "Value" "R_10k_0402"
			(at 213.36 256.54 0)
			(effects
				(font
					(size 1.27 1.27)
					(thickness 0.15)
				)
				(justify left bottom)
				(hide yes)
			)
		)
		(property "Footprint" "antmicro-footprints:R_0402_1005Metric"
			(at 210.82 256.54 0)
			(effects
				(font
					(size 1.27 1.27)
					(thickness 0.15)
				)
				(justify left bottom)
				(hide yes)
			)
		)
		(property "Datasheet" "https://www.bourns.com/docs/product-datasheets/cr.pdf"
			(at 208.28 256.54 0)
			(effects
				(font
					(size 1.27 1.27)
					(thickness 0.15)
				)
				(justify left bottom)
				(hide yes)
			)
		)
		(property "Description" "SMD Chip Resistor, 10 kohm, ± 1%, 62.5 mW, 0402 [1005 Metric], Thick Film, General Purpose"
			(at 226.06 236.22 0)
			(effects
				(font
					(size 1.27 1.27)
				)
				(hide yes)
			)
		)
		(property "MPN" "CR0402-FX-1002GLF"
			(at 205.74 256.54 0)
			(effects
				(font
					(size 1.27 1.27)
					(thickness 0.15)
				)
				(justify left bottom)
				(hide yes)
			)
		)
		(property "Manufacturer" "Bourns"
			(at 203.2 256.54 0)
			(effects
				(font
					(size 1.27 1.27)
					(thickness 0.15)
				)
				(justify left bottom)
				(hide yes)
			)
		)
		(property "License" "Apache-2.0"
			(at 200.66 256.54 0)
			(effects
				(font
					(size 1.27 1.27)
					(thickness 0.15)
				)
				(justify left bottom)
				(hide yes)
			)
		)
		(property "Author" "Antmicro"
			(at 198.12 256.54 0)
			(effects
				(font
					(size 1.27 1.27)
					(thickness 0.15)
				)
				(justify left bottom)
				(hide yes)
			)
		)
		(property "Val" "10k"
			(at 231.14 240.03 90)
			(effects
				(font
					(size 1.27 1.27)
					(thickness 0.15)
				)
				(justify right)
			)
		)
		(property "Tolerance" "1%"
			(at 215.9 256.54 0)
			(effects
				(font
					(size 1.27 1.27)
				)
				(justify left bottom)
				(hide yes)
			)
		)
		(pin "2"
		)
		(pin "1"
		)
		(instances
			(project "jetson-agx-thor-baseboard"
				(path ""
					(reference "R334")
					(unit 1)
				)
			)
		)
	)
	(symbol
		(lib_id "antmicroTestPoints:TP_0.75mm_SMD")
		(at 114.3 116.84 180)
		(unit 1)
		(exclude_from_sim no)
		(in_bom no)
		(on_board yes)
		(dnp no)
		(property "Reference" "TP70"
			(at 110.236 116.078 0)
			(effects
				(font
					(size 1.27 1.27)
				)
				(justify left bottom)
			)
		)
		(property "Value" "TP_0.75mm_SMD"
			(at 104.14 113.03 0)
			(effects
				(font
					(size 1.27 1.27)
					(thickness 0.15)
				)
				(justify left bottom)
				(hide yes)
			)
		)
		(property "Footprint" "antmicro-footprints:TP_SMD_0.75mm"
			(at 104.14 110.49 0)
			(effects
				(font
					(size 1.27 1.27)
					(thickness 0.15)
				)
				(justify left bottom)
				(hide yes)
			)
		)
		(property "Datasheet" ""
			(at 96.52 104.14 0)
			(effects
				(font
					(size 1.27 1.27)
					(thickness 0.15)
				)
				(justify left bottom)
				(hide yes)
			)
		)
		(property "Description" "SMT test point"
			(at 114.3 116.84 0)
			(effects
				(font
					(size 1.27 1.27)
				)
				(hide yes)
			)
		)
		(property "MPN" ""
			(at 103.505 105.41 0)
			(effects
				(font
					(size 1.27 1.27)
					(thickness 0.15)
				)
				(justify left bottom)
				(hide yes)
			)
		)
		(property "Manufacturer" ""
			(at 103.505 110.49 0)
			(effects
				(font
					(size 1.27 1.27)
					(thickness 0.15)
				)
				(justify left bottom)
				(hide yes)
			)
		)
		(property "Author" "Antmicro"
			(at 104.14 107.95 0)
			(effects
				(font
					(size 1.27 1.27)
					(thickness 0.15)
				)
				(justify left bottom)
				(hide yes)
			)
		)
		(property "License" "Apache-2.0"
			(at 104.14 105.41 0)
			(effects
				(font
					(size 1.27 1.27)
					(thickness 0.15)
				)
				(justify left bottom)
				(hide yes)
			)
		)
		(pin "1"
		)
		(instances
			(project "jetson-agx-thor-baseboard"
				(path ""
					(reference "TP70")
					(unit 1)
				)
			)
		)
	)
	(symbol
		(lib_id "antmicroResistors0402:R_10k_0402")
		(at 228.6 171.45 270)
		(mirror x)
		(unit 1)
		(exclude_from_sim no)
		(in_bom no)
		(on_board yes)
		(dnp yes)
		(property "Reference" "R323"
			(at 227.33 167.64 90)
			(effects
				(font
					(size 1.27 1.27)
				)
				(justify right)
			)
		)
		(property "Value" "R_10k_0402"
			(at 215.9 151.13 0)
			(effects
				(font
					(size 1.27 1.27)
					(thickness 0.15)
				)
				(justify left bottom)
				(hide yes)
			)
		)
		(property "Footprint" "antmicro-footprints:R_0402_1005Metric"
			(at 213.36 151.13 0)
			(effects
				(font
					(size 1.27 1.27)
					(thickness 0.15)
				)
				(justify left bottom)
				(hide yes)
			)
		)
		(property "Datasheet" "https://www.bourns.com/docs/product-datasheets/cr.pdf"
			(at 210.82 151.13 0)
			(effects
				(font
					(size 1.27 1.27)
					(thickness 0.15)
				)
				(justify left bottom)
				(hide yes)
			)
		)
		(property "Description" "SMD Chip Resistor, 10 kohm, ± 1%, 62.5 mW, 0402 [1005 Metric], Thick Film, General Purpose"
			(at 228.6 171.45 0)
			(effects
				(font
					(size 1.27 1.27)
				)
				(hide yes)
			)
		)
		(property "Manufacturer" "Bourns"
			(at 205.74 151.13 0)
			(effects
				(font
					(size 1.27 1.27)
					(thickness 0.15)
				)
				(justify left bottom)
				(hide yes)
			)
		)
		(property "MPN" "CR0402-FX-1002GLF"
			(at 208.28 151.13 0)
			(effects
				(font
					(size 1.27 1.27)
					(thickness 0.15)
				)
				(justify left bottom)
				(hide yes)
			)
		)
		(property "Val" "10k"
			(at 227.33 170.18 90)
			(effects
				(font
					(size 1.27 1.27)
					(thickness 0.15)
				)
				(justify right)
			)
		)
		(property "License" "Apache-2.0"
			(at 203.2 151.13 0)
			(effects
				(font
					(size 1.27 1.27)
					(thickness 0.15)
				)
				(justify left bottom)
				(hide yes)
			)
		)
		(property "Author" "Antmicro"
			(at 200.66 151.13 0)
			(effects
				(font
					(size 1.27 1.27)
					(thickness 0.15)
				)
				(justify left bottom)
				(hide yes)
			)
		)
		(property "Tolerance" "1%"
			(at 218.44 151.13 0)
			(effects
				(font
					(size 1.27 1.27)
				)
				(justify left bottom)
				(hide yes)
			)
		)
		(pin "1"
		)
		(pin "2"
		)
		(instances
			(project "jetson-agx-thor-baseboard"
				(path ""
					(reference "R323")
					(unit 1)
				)
			)
		)
	)
	(symbol
		(lib_id "antmicroTestPoints:TP_0.75mm_SMD")
		(at 369.57 151.13 90)
		(unit 1)
		(exclude_from_sim no)
		(in_bom no)
		(on_board yes)
		(dnp no)
		(property "Reference" "TP44"
			(at 369.57 147.32 0)
			(effects
				(font
					(size 1.27 1.27)
				)
				(justify left)
			)
		)
		(property "Value" "TP_0.75mm_SMD"
			(at 373.38 140.97 0)
			(effects
				(font
					(size 1.27 1.27)
					(thickness 0.15)
				)
				(justify left bottom)
				(hide yes)
			)
		)
		(property "Footprint" "antmicro-footprints:TP_SMD_0.75mm"
			(at 375.92 140.97 0)
			(effects
				(font
					(size 1.27 1.27)
					(thickness 0.15)
				)
				(justify left bottom)
				(hide yes)
			)
		)
		(property "Datasheet" ""
			(at 382.27 133.35 0)
			(effects
				(font
					(size 1.27 1.27)
					(thickness 0.15)
				)
				(justify left bottom)
				(hide yes)
			)
		)
		(property "Description" "SMT test point"
			(at 369.57 151.13 0)
			(effects
				(font
					(size 1.27 1.27)
				)
				(hide yes)
			)
		)
		(property "MPN" ""
			(at 381 140.335 0)
			(effects
				(font
					(size 1.27 1.27)
					(thickness 0.15)
				)
				(justify left bottom)
				(hide yes)
			)
		)
		(property "Manufacturer" ""
			(at 375.92 140.335 0)
			(effects
				(font
					(size 1.27 1.27)
					(thickness 0.15)
				)
				(justify left bottom)
				(hide yes)
			)
		)
		(property "Author" "Antmicro"
			(at 378.46 140.97 0)
			(effects
				(font
					(size 1.27 1.27)
					(thickness 0.15)
				)
				(justify left bottom)
				(hide yes)
			)
		)
		(property "License" "Apache-2.0"
			(at 381 140.97 0)
			(effects
				(font
					(size 1.27 1.27)
					(thickness 0.15)
				)
				(justify left bottom)
				(hide yes)
			)
		)
		(pin "1"
		)
		(instances
			(project "jetson-agx-thor-baseboard"
				(path ""
					(reference "TP44")
					(unit 1)
				)
			)
		)
	)
	(symbol
		(lib_id "antmicroCapacitors0402:C_100n_0402")
		(at 99.06 77.47 0)
		(mirror x)
		(unit 1)
		(exclude_from_sim no)
		(in_bom yes)
		(on_board yes)
		(dnp no)
		(property "Reference" "C255"
			(at 105.41 76.2 0)
			(effects
				(font
					(size 1.27 1.27)
				)
			)
		)
		(property "Value" "C_100n_0402"
			(at 119.38 67.31 0)
			(effects
				(font
					(size 1.27 1.27)
					(thickness 0.15)
				)
				(justify left bottom)
				(hide yes)
			)
		)
		(property "Footprint" "antmicro-footprints:C_0402_1005Metric"
			(at 119.38 64.77 0)
			(effects
				(font
					(size 1.27 1.27)
					(thickness 0.15)
				)
				(justify left bottom)
				(hide yes)
			)
		)
		(property "Datasheet" "https://www.murata.com/products/productdetail?partno=GRM155R61H104KE14%23"
			(at 119.38 62.23 0)
			(effects
				(font
					(size 1.27 1.27)
					(thickness 0.15)
				)
				(justify left bottom)
				(hide yes)
			)
		)
		(property "Description" "SMD Multilayer Ceramic Capacitor, 0.1 µF, 50 V, 0402 [1005 Metric], ± 10%, X5R, GRM Series"
			(at 99.06 77.47 0)
			(effects
				(font
					(size 1.27 1.27)
				)
				(hide yes)
			)
		)
		(property "Manufacturer" "Murata"
			(at 119.38 57.15 0)
			(effects
				(font
					(size 1.27 1.27)
					(thickness 0.15)
				)
				(justify left bottom)
				(hide yes)
			)
		)
		(property "MPN" "GRM155R61H104KE14D"
			(at 119.38 59.69 0)
			(effects
				(font
					(size 1.27 1.27)
					(thickness 0.15)
				)
				(justify left bottom)
				(hide yes)
			)
		)
		(property "Val" "100n"
			(at 95.758 76.454 0)
			(effects
				(font
					(size 1.27 1.27)
					(thickness 0.15)
				)
			)
		)
		(property "License" "Apache-2.0"
			(at 119.38 54.61 0)
			(effects
				(font
					(size 1.27 1.27)
					(thickness 0.15)
				)
				(justify left bottom)
				(hide yes)
			)
		)
		(property "Author" "Antmicro"
			(at 119.38 52.07 0)
			(effects
				(font
					(size 1.27 1.27)
					(thickness 0.15)
				)
				(justify left bottom)
				(hide yes)
			)
		)
		(property "Voltage" "50V"
			(at 119.38 49.53 0)
			(effects
				(font
					(size 1.27 1.27)
				)
				(justify left bottom)
				(hide yes)
			)
		)
		(property "Dielectric" "X5R"
			(at 119.38 46.99 0)
			(effects
				(font
					(size 1.27 1.27)
				)
				(justify left bottom)
				(hide yes)
			)
		)
		(pin "1"
		)
		(pin "2"
		)
		(instances
			(project "jetson-agx-thor-baseboard"
				(path ""
					(reference "C255")
					(unit 1)
				)
			)
		)
	)
	(symbol
		(lib_id "antmicropower:GND")
		(at 208.28 107.95 0)
		(unit 1)
		(exclude_from_sim no)
		(in_bom yes)
		(on_board yes)
		(dnp no)
		(property "Reference" "#PWR0201"
			(at 208.28 114.3 0)
			(effects
				(font
					(size 1.27 1.27)
				)
				(justify left bottom)
				(hide yes)
			)
		)
		(property "Value" "GND"
			(at 208.28 111.76 0)
			(effects
				(font
					(size 1.27 1.27)
					(thickness 0.15)
				)
			)
		)
		(property "Footprint" ""
			(at 217.17 115.57 0)
			(effects
				(font
					(size 1.27 1.27)
					(thickness 0.15)
				)
				(justify left bottom)
				(hide yes)
			)
		)
		(property "Datasheet" ""
			(at 217.17 120.65 0)
			(effects
				(font
					(size 1.27 1.27)
					(thickness 0.15)
				)
				(justify left bottom)
				(hide yes)
			)
		)
		(property "Description" ""
			(at 208.28 107.95 0)
			(effects
				(font
					(size 1.27 1.27)
				)
				(hide yes)
			)
		)
		(property "Author" "Antmicro"
			(at 217.17 115.57 0)
			(effects
				(font
					(size 1.27 1.27)
					(thickness 0.15)
				)
				(justify left bottom)
				(hide yes)
			)
		)
		(property "License" "Apache-2.0"
			(at 217.17 118.11 0)
			(effects
				(font
					(size 1.27 1.27)
					(thickness 0.15)
				)
				(justify left bottom)
				(hide yes)
			)
		)
		(pin "1"
		)
		(instances
			(project "jetson-agx-thor-baseboard"
				(path ""
					(reference "#PWR0201")
					(unit 1)
				)
			)
		)
	)
	(symbol
		(lib_id "antmicroTestPoints:TP_0.75mm_SMD")
		(at 114.3 93.98 180)
		(unit 1)
		(exclude_from_sim no)
		(in_bom no)
		(on_board yes)
		(dnp no)
		(property "Reference" "TP67"
			(at 110.236 93.218 0)
			(effects
				(font
					(size 1.27 1.27)
				)
				(justify left bottom)
			)
		)
		(property "Value" "TP_0.75mm_SMD"
			(at 104.14 90.17 0)
			(effects
				(font
					(size 1.27 1.27)
					(thickness 0.15)
				)
				(justify left bottom)
				(hide yes)
			)
		)
		(property "Footprint" "antmicro-footprints:TP_SMD_0.75mm"
			(at 104.14 87.63 0)
			(effects
				(font
					(size 1.27 1.27)
					(thickness 0.15)
				)
				(justify left bottom)
				(hide yes)
			)
		)
		(property "Datasheet" ""
			(at 96.52 81.28 0)
			(effects
				(font
					(size 1.27 1.27)
					(thickness 0.15)
				)
				(justify left bottom)
				(hide yes)
			)
		)
		(property "Description" "SMT test point"
			(at 114.3 93.98 0)
			(effects
				(font
					(size 1.27 1.27)
				)
				(hide yes)
			)
		)
		(property "MPN" ""
			(at 103.505 82.55 0)
			(effects
				(font
					(size 1.27 1.27)
					(thickness 0.15)
				)
				(justify left bottom)
				(hide yes)
			)
		)
		(property "Manufacturer" ""
			(at 103.505 87.63 0)
			(effects
				(font
					(size 1.27 1.27)
					(thickness 0.15)
				)
				(justify left bottom)
				(hide yes)
			)
		)
		(property "Author" "Antmicro"
			(at 104.14 85.09 0)
			(effects
				(font
					(size 1.27 1.27)
					(thickness 0.15)
				)
				(justify left bottom)
				(hide yes)
			)
		)
		(property "License" "Apache-2.0"
			(at 104.14 82.55 0)
			(effects
				(font
					(size 1.27 1.27)
					(thickness 0.15)
				)
				(justify left bottom)
				(hide yes)
			)
		)
		(pin "1"
		)
		(instances
			(project "jetson-agx-thor-baseboard"
				(path ""
					(reference "TP67")
					(unit 1)
				)
			)
		)
	)
	(symbol
		(lib_id "antmicropower:GND")
		(at 35.56 198.12 0)
		(mirror y)
		(unit 1)
		(exclude_from_sim no)
		(in_bom yes)
		(on_board yes)
		(dnp no)
		(property "Reference" "#PWR0195"
			(at 35.56 204.47 0)
			(effects
				(font
					(size 1.27 1.27)
				)
				(justify left bottom)
				(hide yes)
			)
		)
		(property "Value" "GND"
			(at 35.56 201.93 0)
			(effects
				(font
					(size 1.27 1.27)
					(thickness 0.15)
				)
			)
		)
		(property "Footprint" ""
			(at 26.67 205.74 0)
			(effects
				(font
					(size 1.27 1.27)
					(thickness 0.15)
				)
				(justify left bottom)
				(hide yes)
			)
		)
		(property "Datasheet" ""
			(at 26.67 210.82 0)
			(effects
				(font
					(size 1.27 1.27)
					(thickness 0.15)
				)
				(justify left bottom)
				(hide yes)
			)
		)
		(property "Description" ""
			(at 35.56 198.12 0)
			(effects
				(font
					(size 1.27 1.27)
				)
				(hide yes)
			)
		)
		(property "Author" "Antmicro"
			(at 26.67 205.74 0)
			(effects
				(font
					(size 1.27 1.27)
					(thickness 0.15)
				)
				(justify left bottom)
				(hide yes)
			)
		)
		(property "License" "Apache-2.0"
			(at 26.67 208.28 0)
			(effects
				(font
					(size 1.27 1.27)
					(thickness 0.15)
				)
				(justify left bottom)
				(hide yes)
			)
		)
		(pin "1"
		)
		(instances
			(project "jetson-agx-thor-baseboard"
				(path ""
					(reference "#PWR0195")
					(unit 1)
				)
			)
		)
	)
	(symbol
		(lib_id "antmicroResistors0402:R_0R_0402")
		(at 52.07 246.38 0)
		(mirror x)
		(unit 1)
		(exclude_from_sim no)
		(in_bom no)
		(on_board yes)
		(dnp yes)
		(fields_autoplaced yes)
		(property "Reference" "R89"
			(at 52.07 245.745 0)
			(effects
				(font
					(size 1.27 1.27)
				)
				(justify right top)
			)
		)
		(property "Value" "R_0R_0402"
			(at 72.39 233.68 0)
			(effects
				(font
					(size 1.27 1.27)
					(thickness 0.15)
				)
				(justify left bottom)
				(hide yes)
			)
		)
		(property "Footprint" "antmicro-footprints:R_0402_1005Metric"
			(at 72.39 231.14 0)
			(effects
				(font
					(size 1.27 1.27)
					(thickness 0.15)
				)
				(justify left bottom)
				(hide yes)
			)
		)
		(property "Datasheet" "https://industrial.panasonic.com/cdbs/www-data/pdf/RDA0000/AOA0000C301.pdf"
			(at 72.39 228.6 0)
			(effects
				(font
					(size 1.27 1.27)
					(thickness 0.15)
				)
				(justify left bottom)
				(hide yes)
			)
		)
		(property "Description" "SMD Chip Resistor, Jumper, 0 ohm, 100 mW, 0402 [1005 Metric], Thick Film, General Purpose"
			(at 52.07 246.38 0)
			(effects
				(font
					(size 1.27 1.27)
				)
				(hide yes)
			)
		)
		(property "Manufacturer" "Panasonic"
			(at 72.39 223.52 0)
			(effects
				(font
					(size 1.27 1.27)
					(thickness 0.15)
				)
				(justify left bottom)
				(hide yes)
			)
		)
		(property "MPN" "ERJ2GE0R00X"
			(at 72.39 226.06 0)
			(effects
				(font
					(size 1.27 1.27)
					(thickness 0.15)
				)
				(justify left bottom)
				(hide yes)
			)
		)
		(property "Val" "0R"
			(at 59.69 245.745 0)
			(effects
				(font
					(size 1.27 1.27)
					(thickness 0.15)
				)
				(justify right top)
			)
		)
		(property "License" "Apache-2.0"
			(at 72.39 220.98 0)
			(effects
				(font
					(size 1.27 1.27)
					(thickness 0.15)
				)
				(justify left bottom)
				(hide yes)
			)
		)
		(property "Author" "Antmicro"
			(at 72.39 218.44 0)
			(effects
				(font
					(size 1.27 1.27)
					(thickness 0.15)
				)
				(justify left bottom)
				(hide yes)
			)
		)
		(property "Tolerance" "~"
			(at 72.39 236.22 0)
			(effects
				(font
					(size 1.27 1.27)
				)
				(justify left bottom)
				(hide yes)
			)
		)
		(property "Current" "1A"
			(at 72.39 215.9 0)
			(effects
				(font
					(size 1.27 1.27)
					(thickness 0.15)
				)
				(justify left bottom)
				(hide yes)
			)
		)
		(pin "1"
		)
		(pin "2"
		)
		(instances
			(project "jetson-agx-thor-baseboard"
				(path ""
					(reference "R89")
					(unit 1)
				)
			)
		)
	)
	(symbol
		(lib_id "antmicroTransistorsFETsMOSFETsArrays:DMC2400UV-7")
		(at 223.52 241.3 180)
		(unit 1)
		(exclude_from_sim no)
		(in_bom yes)
		(on_board yes)
		(dnp no)
		(property "Reference" "Q27"
			(at 217.17 244.348 0)
			(effects
				(font
					(size 1.27 1.27)
					(thickness 0.15)
				)
			)
		)
		(property "Value" "DMC2400UV-7"
			(at 195.58 236.22 0)
			(effects
				(font
					(size 1.27 1.27)
					(thickness 0.15)
				)
				(justify left bottom)
				(hide yes)
			)
		)
		(property "Footprint" "antmicro-footprints:SOT-563"
			(at 195.58 233.68 0)
			(effects
				(font
					(size 1.27 1.27)
					(thickness 0.15)
				)
				(justify left bottom)
				(hide yes)
			)
		)
		(property "Datasheet" "https://www.mouser.com/datasheet/2/115/DIOD_S_A0010038249_1-2543538.pdf"
			(at 195.58 231.14 0)
			(effects
				(font
					(size 1.27 1.27)
					(thickness 0.15)
				)
				(justify left bottom)
				(hide yes)
			)
		)
		(property "Description" "Dual MOSFET, Complementary N and P Channel, 20 V, 20 V, 1.03 A, 1.03 A, 0.3 ohm"
			(at 195.58 218.44 0)
			(effects
				(font
					(size 1.27 1.27)
				)
				(justify left bottom)
				(hide yes)
			)
		)
		(property "MPN" "DMC2400UV-7"
			(at 217.17 246.888 0)
			(effects
				(font
					(size 1.27 1.27)
					(thickness 0.15)
				)
			)
		)
		(property "Manufacturer" "Diodes Incorporated"
			(at 195.58 226.06 0)
			(effects
				(font
					(size 1.27 1.27)
					(thickness 0.15)
				)
				(justify left bottom)
				(hide yes)
			)
		)
		(property "Author" "Antmicro"
			(at 195.58 223.52 0)
			(effects
				(font
					(size 1.27 1.27)
					(thickness 0.15)
				)
				(justify left bottom)
				(hide yes)
			)
		)
		(property "License" "Apache-2.0"
			(at 195.58 220.98 0)
			(effects
				(font
					(size 1.27 1.27)
					(thickness 0.15)
				)
				(justify left bottom)
				(hide yes)
			)
		)
		(pin "5"
		)
		(pin "3"
		)
		(pin "6"
		)
		(pin "2"
		)
		(pin "1"
		)
		(pin "4"
		)
		(instances
			(project "jetson-agx-thor-baseboard"
				(path ""
					(reference "Q27")
					(unit 1)
				)
			)
		)
	)
	(symbol
		(lib_id "antmicropower:GND")
		(at 82.55 153.67 0)
		(mirror y)
		(unit 1)
		(exclude_from_sim no)
		(in_bom yes)
		(on_board yes)
		(dnp no)
		(property "Reference" "#PWR0191"
			(at 82.55 160.02 0)
			(effects
				(font
					(size 1.27 1.27)
				)
				(justify left bottom)
				(hide yes)
			)
		)
		(property "Value" "GND"
			(at 82.55 157.48 0)
			(effects
				(font
					(size 1.27 1.27)
					(thickness 0.15)
				)
			)
		)
		(property "Footprint" ""
			(at 73.66 161.29 0)
			(effects
				(font
					(size 1.27 1.27)
					(thickness 0.15)
				)
				(justify left bottom)
				(hide yes)
			)
		)
		(property "Datasheet" ""
			(at 73.66 166.37 0)
			(effects
				(font
					(size 1.27 1.27)
					(thickness 0.15)
				)
				(justify left bottom)
				(hide yes)
			)
		)
		(property "Description" ""
			(at 82.55 153.67 0)
			(effects
				(font
					(size 1.27 1.27)
				)
				(hide yes)
			)
		)
		(property "Author" "Antmicro"
			(at 73.66 161.29 0)
			(effects
				(font
					(size 1.27 1.27)
					(thickness 0.15)
				)
				(justify left bottom)
				(hide yes)
			)
		)
		(property "License" "Apache-2.0"
			(at 73.66 163.83 0)
			(effects
				(font
					(size 1.27 1.27)
					(thickness 0.15)
				)
				(justify left bottom)
				(hide yes)
			)
		)
		(pin "1"
		)
		(instances
			(project "jetson-agx-thor-baseboard"
				(path ""
					(reference "#PWR0191")
					(unit 1)
				)
			)
		)
	)
	(symbol
		(lib_id "antmicropower:GND")
		(at 27.94 198.12 0)
		(mirror y)
		(unit 1)
		(exclude_from_sim no)
		(in_bom yes)
		(on_board yes)
		(dnp no)
		(property "Reference" "#PWR0193"
			(at 27.94 204.47 0)
			(effects
				(font
					(size 1.27 1.27)
				)
				(justify left bottom)
				(hide yes)
			)
		)
		(property "Value" "GND"
			(at 27.94 201.93 0)
			(effects
				(font
					(size 1.27 1.27)
					(thickness 0.15)
				)
			)
		)
		(property "Footprint" ""
			(at 19.05 205.74 0)
			(effects
				(font
					(size 1.27 1.27)
					(thickness 0.15)
				)
				(justify left bottom)
				(hide yes)
			)
		)
		(property "Datasheet" ""
			(at 19.05 210.82 0)
			(effects
				(font
					(size 1.27 1.27)
					(thickness 0.15)
				)
				(justify left bottom)
				(hide yes)
			)
		)
		(property "Description" ""
			(at 27.94 198.12 0)
			(effects
				(font
					(size 1.27 1.27)
				)
				(hide yes)
			)
		)
		(property "Author" "Antmicro"
			(at 19.05 205.74 0)
			(effects
				(font
					(size 1.27 1.27)
					(thickness 0.15)
				)
				(justify left bottom)
				(hide yes)
			)
		)
		(property "License" "Apache-2.0"
			(at 19.05 208.28 0)
			(effects
				(font
					(size 1.27 1.27)
					(thickness 0.15)
				)
				(justify left bottom)
				(hide yes)
			)
		)
		(pin "1"
		)
		(instances
			(project "jetson-agx-thor-baseboard"
				(path ""
					(reference "#PWR0193")
					(unit 1)
				)
			)
		)
	)
	(symbol
		(lib_id "antmicroTVSDiodes:TPD4E05U06QDQARQ1")
		(at 322.58 232.41 270)
		(unit 1)
		(exclude_from_sim no)
		(in_bom yes)
		(on_board yes)
		(dnp no)
		(property "Reference" "U17"
			(at 311.912 243.586 90)
			(effects
				(font
					(size 1.27 1.27)
				)
			)
		)
		(property "Value" "TPD4E05U06QDQARQ1"
			(at 312.42 256.54 0)
			(effects
				(font
					(size 1.27 1.27)
					(thickness 0.15)
				)
				(justify left bottom)
				(hide yes)
			)
		)
		(property "Footprint" "antmicro-footprints:USON-10_2.5x1mm_P0.5mm"
			(at 317.5 256.54 0)
			(effects
				(font
					(size 1.27 1.27)
					(thickness 0.15)
				)
				(justify left bottom)
				(hide yes)
			)
		)
		(property "Datasheet" "https://www.ti.com/lit/ds/symlink/tpd4e05u06-q1.pdf?HQS=dis-mous-null-mousermode-dsf-pf-null-wwe&ts=1663591265741&ref_url=https%253A%252F%252Fwww.mouser.com%252F"
			(at 314.96 256.54 0)
			(effects
				(font
					(size 1.27 1.27)
					(thickness 0.15)
				)
				(justify left bottom)
				(hide yes)
			)
		)
		(property "Description" "TVS diode array, 12 kV, USON-10, 5.5 V, 0.5 pF"
			(at 322.58 232.41 0)
			(effects
				(font
					(size 1.27 1.27)
				)
				(hide yes)
			)
		)
		(property "Manufacturer" "Texas Instruments"
			(at 309.88 256.54 0)
			(effects
				(font
					(size 1.27 1.27)
					(thickness 0.15)
				)
				(justify left bottom)
				(hide yes)
			)
		)
		(property "MPN" "TPD4E05U06QDQARQ1"
			(at 311.912 246.126 90)
			(effects
				(font
					(size 1.27 1.27)
					(thickness 0.15)
				)
			)
		)
		(property "Author" "Antmicro"
			(at 307.34 256.54 0)
			(effects
				(font
					(size 1.27 1.27)
					(thickness 0.15)
				)
				(justify left bottom)
				(hide yes)
			)
		)
		(property "License" "Apache-2.0"
			(at 304.8 256.54 0)
			(effects
				(font
					(size 1.27 1.27)
					(thickness 0.15)
				)
				(justify left bottom)
				(hide yes)
			)
		)
		(pin "1"
		)
		(pin "10"
		)
		(pin "2"
		)
		(pin "3"
		)
		(pin "4"
		)
		(pin "5"
		)
		(pin "6"
		)
		(pin "7"
		)
		(pin "8"
		)
		(pin "9"
		)
		(instances
			(project "jetson-agx-thor-baseboard"
				(path ""
					(reference "U17")
					(unit 1)
				)
			)
		)
	)
	(symbol
		(lib_id "antmicroTestPoints:TP_0.75mm_SMD")
		(at 114.3 114.3 180)
		(unit 1)
		(exclude_from_sim no)
		(in_bom no)
		(on_board yes)
		(dnp no)
		(property "Reference" "TP69"
			(at 110.236 113.538 0)
			(effects
				(font
					(size 1.27 1.27)
				)
				(justify left bottom)
			)
		)
		(property "Value" "TP_0.75mm_SMD"
			(at 104.14 110.49 0)
			(effects
				(font
					(size 1.27 1.27)
					(thickness 0.15)
				)
				(justify left bottom)
				(hide yes)
			)
		)
		(property "Footprint" "antmicro-footprints:TP_SMD_0.75mm"
			(at 104.14 107.95 0)
			(effects
				(font
					(size 1.27 1.27)
					(thickness 0.15)
				)
				(justify left bottom)
				(hide yes)
			)
		)
		(property "Datasheet" ""
			(at 96.52 101.6 0)
			(effects
				(font
					(size 1.27 1.27)
					(thickness 0.15)
				)
				(justify left bottom)
				(hide yes)
			)
		)
		(property "Description" "SMT test point"
			(at 114.3 114.3 0)
			(effects
				(font
					(size 1.27 1.27)
				)
				(hide yes)
			)
		)
		(property "MPN" ""
			(at 103.505 102.87 0)
			(effects
				(font
					(size 1.27 1.27)
					(thickness 0.15)
				)
				(justify left bottom)
				(hide yes)
			)
		)
		(property "Manufacturer" ""
			(at 103.505 107.95 0)
			(effects
				(font
					(size 1.27 1.27)
					(thickness 0.15)
				)
				(justify left bottom)
				(hide yes)
			)
		)
		(property "Author" "Antmicro"
			(at 104.14 105.41 0)
			(effects
				(font
					(size 1.27 1.27)
					(thickness 0.15)
				)
				(justify left bottom)
				(hide yes)
			)
		)
		(property "License" "Apache-2.0"
			(at 104.14 102.87 0)
			(effects
				(font
					(size 1.27 1.27)
					(thickness 0.15)
				)
				(justify left bottom)
				(hide yes)
			)
		)
		(pin "1"
		)
		(instances
			(project "jetson-agx-thor-baseboard"
				(path ""
					(reference "TP69")
					(unit 1)
				)
			)
		)
	)
	(symbol
		(lib_id "antmicroResistors0402:R_0R_0402")
		(at 116.84 137.16 0)
		(unit 1)
		(exclude_from_sim no)
		(in_bom no)
		(on_board yes)
		(dnp yes)
		(fields_autoplaced yes)
		(property "Reference" "R40"
			(at 116.84 136.525 0)
			(effects
				(font
					(size 1.27 1.27)
				)
				(justify right bottom)
			)
		)
		(property "Value" "R_0R_0402"
			(at 137.16 149.86 0)
			(effects
				(font
					(size 1.27 1.27)
					(thickness 0.15)
				)
				(justify left bottom)
				(hide yes)
			)
		)
		(property "Footprint" "antmicro-footprints:R_0402_1005Metric"
			(at 137.16 152.4 0)
			(effects
				(font
					(size 1.27 1.27)
					(thickness 0.15)
				)
				(justify left bottom)
				(hide yes)
			)
		)
		(property "Datasheet" "https://industrial.panasonic.com/cdbs/www-data/pdf/RDA0000/AOA0000C301.pdf"
			(at 137.16 154.94 0)
			(effects
				(font
					(size 1.27 1.27)
					(thickness 0.15)
				)
				(justify left bottom)
				(hide yes)
			)
		)
		(property "Description" "SMD Chip Resistor, Jumper, 0 ohm, 100 mW, 0402 [1005 Metric], Thick Film, General Purpose"
			(at 116.84 137.16 0)
			(effects
				(font
					(size 1.27 1.27)
				)
				(hide yes)
			)
		)
		(property "Manufacturer" "Panasonic"
			(at 137.16 160.02 0)
			(effects
				(font
					(size 1.27 1.27)
					(thickness 0.15)
				)
				(justify left bottom)
				(hide yes)
			)
		)
		(property "MPN" "ERJ2GE0R00X"
			(at 137.16 157.48 0)
			(effects
				(font
					(size 1.27 1.27)
					(thickness 0.15)
				)
				(justify left bottom)
				(hide yes)
			)
		)
		(property "Val" "0R"
			(at 124.46 136.525 0)
			(effects
				(font
					(size 1.27 1.27)
					(thickness 0.15)
				)
				(justify right bottom)
			)
		)
		(property "License" "Apache-2.0"
			(at 137.16 162.56 0)
			(effects
				(font
					(size 1.27 1.27)
					(thickness 0.15)
				)
				(justify left bottom)
				(hide yes)
			)
		)
		(property "Author" "Antmicro"
			(at 137.16 165.1 0)
			(effects
				(font
					(size 1.27 1.27)
					(thickness 0.15)
				)
				(justify left bottom)
				(hide yes)
			)
		)
		(property "Tolerance" "~"
			(at 137.16 147.32 0)
			(effects
				(font
					(size 1.27 1.27)
				)
				(justify left bottom)
				(hide yes)
			)
		)
		(property "Current" "1A"
			(at 137.16 167.64 0)
			(effects
				(font
					(size 1.27 1.27)
					(thickness 0.15)
				)
				(justify left bottom)
				(hide yes)
			)
		)
		(pin "1"
		)
		(pin "2"
		)
		(instances
			(project "jetson-agx-thor-baseboard"
				(path ""
					(reference "R40")
					(unit 1)
				)
			)
		)
	)
	(symbol
		(lib_id "antmicroResistors0402:R_470R_0402")
		(at 393.7 38.1 90)
		(unit 1)
		(exclude_from_sim no)
		(in_bom yes)
		(on_board yes)
		(dnp no)
		(property "Reference" "R74"
			(at 394.97 34.29 90)
			(effects
				(font
					(size 1.27 1.27)
				)
				(justify right)
			)
		)
		(property "Value" "R_470R_0402"
			(at 406.4 17.78 0)
			(effects
				(font
					(size 1.27 1.27)
					(thickness 0.15)
				)
				(justify left bottom)
				(hide yes)
			)
		)
		(property "Footprint" "antmicro-footprints:R_0402_1005Metric"
			(at 408.94 17.78 0)
			(effects
				(font
					(size 1.27 1.27)
					(thickness 0.15)
				)
				(justify left bottom)
				(hide yes)
			)
		)
		(property "Datasheet" "https://www.bourns.com/docs/product-datasheets/cr.pdf"
			(at 411.48 17.78 0)
			(effects
				(font
					(size 1.27 1.27)
					(thickness 0.15)
				)
				(justify left bottom)
				(hide yes)
			)
		)
		(property "Description" "SMD Chip Resistor, 470 ohm, ± 1%, 62.5 mW, 0402 [1005 Metric], Thick Film, General Purpose"
			(at 393.7 38.1 0)
			(effects
				(font
					(size 1.27 1.27)
				)
				(hide yes)
			)
		)
		(property "Manufacturer" "Bourns"
			(at 416.56 17.78 0)
			(effects
				(font
					(size 1.27 1.27)
					(thickness 0.15)
				)
				(justify left bottom)
				(hide yes)
			)
		)
		(property "MPN" "CR0402-FX-4700GLF"
			(at 414.02 17.78 0)
			(effects
				(font
					(size 1.27 1.27)
					(thickness 0.15)
				)
				(justify left bottom)
				(hide yes)
			)
		)
		(property "Val" "470R"
			(at 394.97 36.83 90)
			(effects
				(font
					(size 1.27 1.27)
					(thickness 0.15)
				)
				(justify right)
			)
		)
		(property "License" "Apache-2.0"
			(at 419.1 17.78 0)
			(effects
				(font
					(size 1.27 1.27)
					(thickness 0.15)
				)
				(justify left bottom)
				(hide yes)
			)
		)
		(property "Author" "Antmicro"
			(at 421.64 17.78 0)
			(effects
				(font
					(size 1.27 1.27)
					(thickness 0.15)
				)
				(justify left bottom)
				(hide yes)
			)
		)
		(property "Tolerance" "1%"
			(at 403.86 17.78 0)
			(effects
				(font
					(size 1.27 1.27)
				)
				(justify left bottom)
				(hide yes)
			)
		)
		(pin "1"
		)
		(pin "2"
		)
		(instances
			(project "jetson-agx-thor-baseboard"
				(path ""
					(reference "R74")
					(unit 1)
				)
			)
		)
	)
	(symbol
		(lib_id "antmicropower:GND")
		(at 226.06 266.7 0)
		(mirror y)
		(unit 1)
		(exclude_from_sim no)
		(in_bom yes)
		(on_board yes)
		(dnp no)
		(property "Reference" "#PWR0693"
			(at 226.06 273.05 0)
			(effects
				(font
					(size 1.27 1.27)
				)
				(justify left bottom)
				(hide yes)
			)
		)
		(property "Value" "GND"
			(at 226.06 270.51 0)
			(effects
				(font
					(size 1.27 1.27)
					(thickness 0.15)
				)
			)
		)
		(property "Footprint" ""
			(at 217.17 274.32 0)
			(effects
				(font
					(size 1.27 1.27)
					(thickness 0.15)
				)
				(justify left bottom)
				(hide yes)
			)
		)
		(property "Datasheet" ""
			(at 217.17 279.4 0)
			(effects
				(font
					(size 1.27 1.27)
					(thickness 0.15)
				)
				(justify left bottom)
				(hide yes)
			)
		)
		(property "Description" ""
			(at 226.06 266.7 0)
			(effects
				(font
					(size 1.27 1.27)
				)
				(hide yes)
			)
		)
		(property "Author" "Antmicro"
			(at 217.17 274.32 0)
			(effects
				(font
					(size 1.27 1.27)
					(thickness 0.15)
				)
				(justify left bottom)
				(hide yes)
			)
		)
		(property "License" "Apache-2.0"
			(at 217.17 276.86 0)
			(effects
				(font
					(size 1.27 1.27)
					(thickness 0.15)
				)
				(justify left bottom)
				(hide yes)
			)
		)
		(pin "1"
		)
		(instances
			(project "jetson-agx-thor-baseboard"
				(path ""
					(reference "#PWR0693")
					(unit 1)
				)
			)
		)
	)
	(symbol
		(lib_id "antmicropower:+3V3")
		(at 17.78 58.42 0)
		(unit 1)
		(exclude_from_sim no)
		(in_bom yes)
		(on_board yes)
		(dnp no)
		(property "Reference" "#PWR0183"
			(at 33.02 58.42 0)
			(effects
				(font
					(size 1.27 1.27)
					(thickness 0.15)
				)
				(justify left bottom)
				(hide yes)
			)
		)
		(property "Value" "+3V3"
			(at 21.336 56.642 0)
			(effects
				(font
					(size 1.27 1.27)
					(thickness 0.15)
				)
			)
		)
		(property "Footprint" ""
			(at 33.02 66.04 0)
			(effects
				(font
					(size 1.27 1.27)
					(thickness 0.15)
				)
				(justify left bottom)
				(hide yes)
			)
		)
		(property "Datasheet" ""
			(at 33.02 68.58 0)
			(effects
				(font
					(size 1.27 1.27)
					(thickness 0.15)
				)
				(justify left bottom)
				(hide yes)
			)
		)
		(property "Description" ""
			(at 17.78 58.42 0)
			(effects
				(font
					(size 1.27 1.27)
				)
				(hide yes)
			)
		)
		(property "Author" "Antmicro"
			(at 33.02 60.96 0)
			(effects
				(font
					(size 1.27 1.27)
					(thickness 0.15)
				)
				(justify left bottom)
				(hide yes)
			)
		)
		(property "License" "Apache-2.0"
			(at 33.02 63.5 0)
			(effects
				(font
					(size 1.27 1.27)
					(thickness 0.15)
				)
				(justify left bottom)
				(hide yes)
			)
		)
		(pin "1"
		)
		(instances
			(project "jetson-agx-thor-baseboard"
				(path ""
					(reference "#PWR0183")
					(unit 1)
				)
			)
		)
	)
	(symbol
		(lib_id "antmicropower:GND")
		(at 308.61 234.95 0)
		(unit 1)
		(exclude_from_sim no)
		(in_bom yes)
		(on_board yes)
		(dnp no)
		(property "Reference" "#PWR0165"
			(at 308.61 241.3 0)
			(effects
				(font
					(size 1.27 1.27)
				)
				(justify left bottom)
				(hide yes)
			)
		)
		(property "Value" "GND"
			(at 308.61 238.76 0)
			(effects
				(font
					(size 1.27 1.27)
					(thickness 0.15)
				)
			)
		)
		(property "Footprint" ""
			(at 317.5 242.57 0)
			(effects
				(font
					(size 1.27 1.27)
					(thickness 0.15)
				)
				(justify left bottom)
				(hide yes)
			)
		)
		(property "Datasheet" ""
			(at 317.5 247.65 0)
			(effects
				(font
					(size 1.27 1.27)
					(thickness 0.15)
				)
				(justify left bottom)
				(hide yes)
			)
		)
		(property "Description" ""
			(at 308.61 234.95 0)
			(effects
				(font
					(size 1.27 1.27)
				)
				(hide yes)
			)
		)
		(property "Author" "Antmicro"
			(at 317.5 242.57 0)
			(effects
				(font
					(size 1.27 1.27)
					(thickness 0.15)
				)
				(justify left bottom)
				(hide yes)
			)
		)
		(property "License" "Apache-2.0"
			(at 317.5 245.11 0)
			(effects
				(font
					(size 1.27 1.27)
					(thickness 0.15)
				)
				(justify left bottom)
				(hide yes)
			)
		)
		(pin "1"
		)
		(instances
			(project "jetson-agx-thor-baseboard"
				(path ""
					(reference "#PWR0165")
					(unit 1)
				)
			)
		)
	)
	(symbol
		(lib_id "antmicroResistors0402:R_10k_0402")
		(at 148.59 256.54 90)
		(mirror x)
		(unit 1)
		(exclude_from_sim no)
		(in_bom yes)
		(on_board yes)
		(dnp no)
		(property "Reference" "R303"
			(at 142.24 257.81 90)
			(effects
				(font
					(size 1.27 1.27)
					(thickness 0.15)
				)
				(justify right)
			)
		)
		(property "Value" "R_10k_0402"
			(at 161.29 276.86 0)
			(effects
				(font
					(size 1.27 1.27)
					(thickness 0.15)
				)
				(justify left bottom)
				(hide yes)
			)
		)
		(property "Footprint" "antmicro-footprints:R_0402_1005Metric"
			(at 163.83 276.86 0)
			(effects
				(font
					(size 1.27 1.27)
					(thickness 0.15)
				)
				(justify left bottom)
				(hide yes)
			)
		)
		(property "Datasheet" "https://www.bourns.com/docs/product-datasheets/cr.pdf"
			(at 166.37 276.86 0)
			(effects
				(font
					(size 1.27 1.27)
					(thickness 0.15)
				)
				(justify left bottom)
				(hide yes)
			)
		)
		(property "Description" "SMD Chip Resistor, 10 kohm, ± 1%, 62.5 mW, 0402 [1005 Metric], Thick Film, General Purpose"
			(at 148.59 256.54 0)
			(effects
				(font
					(size 1.27 1.27)
				)
				(hide yes)
			)
		)
		(property "MPN" "CR0402-FX-1002GLF"
			(at 168.91 276.86 0)
			(effects
				(font
					(size 1.27 1.27)
					(thickness 0.15)
				)
				(justify left bottom)
				(hide yes)
			)
		)
		(property "Manufacturer" "Bourns"
			(at 171.45 276.86 0)
			(effects
				(font
					(size 1.27 1.27)
					(thickness 0.15)
				)
				(justify left bottom)
				(hide yes)
			)
		)
		(property "License" "Apache-2.0"
			(at 173.99 276.86 0)
			(effects
				(font
					(size 1.27 1.27)
					(thickness 0.15)
				)
				(justify left bottom)
				(hide yes)
			)
		)
		(property "Author" "Antmicro"
			(at 176.53 276.86 0)
			(effects
				(font
					(size 1.27 1.27)
					(thickness 0.15)
				)
				(justify left bottom)
				(hide yes)
			)
		)
		(property "Val" "10k"
			(at 143.51 260.35 90)
			(effects
				(font
					(size 1.27 1.27)
					(thickness 0.15)
				)
				(justify right)
			)
		)
		(property "Tolerance" "1%"
			(at 158.75 276.86 0)
			(effects
				(font
					(size 1.27 1.27)
				)
				(justify left bottom)
				(hide yes)
			)
		)
		(pin "2"
		)
		(pin "1"
		)
		(instances
			(project "jetson-agx-thor-baseboard"
				(path ""
					(reference "R303")
					(unit 1)
				)
			)
		)
	)
	(symbol
		(lib_id "antmicroPMICPowerDistributionSwitchesLoadDrivers:AP22615A_TSOT26")
		(at 317.5 153.67 0)
		(unit 1)
		(exclude_from_sim no)
		(in_bom yes)
		(on_board yes)
		(dnp no)
		(property "Reference" "U20"
			(at 325.12 147.32 0)
			(effects
				(font
					(size 1.27 1.27)
				)
			)
		)
		(property "Value" "AP22615A_TSOT26"
			(at 347.98 158.75 0)
			(effects
				(font
					(size 1.27 1.27)
					(thickness 0.15)
				)
				(justify left bottom)
				(hide yes)
			)
		)
		(property "Footprint" "antmicro-footprints:TSOT23-6"
			(at 347.98 161.29 0)
			(effects
				(font
					(size 1.27 1.27)
					(thickness 0.15)
				)
				(justify left bottom)
				(hide yes)
			)
		)
		(property "Datasheet" "https://www.mouser.com/datasheet/2/115/DIOD_S_A0008958405_1-2543193.pdf"
			(at 347.98 163.83 0)
			(effects
				(font
					(size 1.27 1.27)
					(thickness 0.15)
				)
				(justify left bottom)
				(hide yes)
			)
		)
		(property "Description" "Power Load Distribution Switch, High Side, Active High, 1 Output, 5.5 V, 3.6 A, 0.04 ohm, TSOT-26-6"
			(at 317.5 153.67 0)
			(effects
				(font
					(size 1.27 1.27)
				)
				(hide yes)
			)
		)
		(property "MPN" "AP22615AWU-7"
			(at 325.12 149.86 0)
			(effects
				(font
					(size 1.27 1.27)
					(thickness 0.15)
				)
			)
		)
		(property "Manufacturer" "Diodes Incorporated"
			(at 347.98 168.91 0)
			(effects
				(font
					(size 1.27 1.27)
					(thickness 0.15)
				)
				(justify left bottom)
				(hide yes)
			)
		)
		(property "Author" "Antmicro"
			(at 347.98 171.45 0)
			(effects
				(font
					(size 1.27 1.27)
					(thickness 0.15)
				)
				(justify left bottom)
				(hide yes)
			)
		)
		(property "License" "Apache-2.0"
			(at 347.98 173.99 0)
			(effects
				(font
					(size 1.27 1.27)
					(thickness 0.15)
				)
				(justify left bottom)
				(hide yes)
			)
		)
		(pin "1"
		)
		(pin "2"
		)
		(pin "3"
		)
		(pin "4"
		)
		(pin "5"
		)
		(pin "6"
		)
		(instances
			(project "jetson-agx-thor-baseboard"
				(path ""
					(reference "U20")
					(unit 1)
				)
			)
		)
	)
	(symbol
		(lib_id "antmicroResistors0402:R_10k_0402")
		(at 92.71 165.1 270)
		(unit 1)
		(exclude_from_sim no)
		(in_bom yes)
		(on_board yes)
		(dnp no)
		(property "Reference" "R81"
			(at 97.79 166.37 90)
			(effects
				(font
					(size 1.27 1.27)
					(thickness 0.15)
				)
				(justify right)
			)
		)
		(property "Value" "R_10k_0402"
			(at 80.01 185.42 0)
			(effects
				(font
					(size 1.27 1.27)
					(thickness 0.15)
				)
				(justify left bottom)
				(hide yes)
			)
		)
		(property "Footprint" "antmicro-footprints:R_0402_1005Metric"
			(at 77.47 185.42 0)
			(effects
				(font
					(size 1.27 1.27)
					(thickness 0.15)
				)
				(justify left bottom)
				(hide yes)
			)
		)
		(property "Datasheet" "https://www.bourns.com/docs/product-datasheets/cr.pdf"
			(at 74.93 185.42 0)
			(effects
				(font
					(size 1.27 1.27)
					(thickness 0.15)
				)
				(justify left bottom)
				(hide yes)
			)
		)
		(property "Description" "SMD Chip Resistor, 10 kohm, ± 1%, 62.5 mW, 0402 [1005 Metric], Thick Film, General Purpose"
			(at 92.71 165.1 0)
			(effects
				(font
					(size 1.27 1.27)
				)
				(hide yes)
			)
		)
		(property "MPN" "CR0402-FX-1002GLF"
			(at 72.39 185.42 0)
			(effects
				(font
					(size 1.27 1.27)
					(thickness 0.15)
				)
				(justify left bottom)
				(hide yes)
			)
		)
		(property "Manufacturer" "Bourns"
			(at 69.85 185.42 0)
			(effects
				(font
					(size 1.27 1.27)
					(thickness 0.15)
				)
				(justify left bottom)
				(hide yes)
			)
		)
		(property "License" "Apache-2.0"
			(at 67.31 185.42 0)
			(effects
				(font
					(size 1.27 1.27)
					(thickness 0.15)
				)
				(justify left bottom)
				(hide yes)
			)
		)
		(property "Author" "Antmicro"
			(at 64.77 185.42 0)
			(effects
				(font
					(size 1.27 1.27)
					(thickness 0.15)
				)
				(justify left bottom)
				(hide yes)
			)
		)
		(property "Val" "10k"
			(at 97.79 168.91 90)
			(effects
				(font
					(size 1.27 1.27)
					(thickness 0.15)
				)
				(justify right)
			)
		)
		(property "Tolerance" "1%"
			(at 82.55 185.42 0)
			(effects
				(font
					(size 1.27 1.27)
				)
				(justify left bottom)
				(hide yes)
			)
		)
		(pin "2"
		)
		(pin "1"
		)
		(instances
			(project "jetson-agx-thor-baseboard"
				(path ""
					(reference "R81")
					(unit 1)
				)
			)
		)
	)
	(symbol
		(lib_id "antmicroResistors0402:R_10k_0402")
		(at 27.94 88.9 270)
		(unit 1)
		(exclude_from_sim no)
		(in_bom yes)
		(on_board yes)
		(dnp no)
		(property "Reference" "R67"
			(at 33.274 90.17 90)
			(effects
				(font
					(size 1.27 1.27)
					(thickness 0.15)
				)
				(justify right)
			)
		)
		(property "Value" "R_10k_0402"
			(at 15.24 109.22 0)
			(effects
				(font
					(size 1.27 1.27)
					(thickness 0.15)
				)
				(justify left bottom)
				(hide yes)
			)
		)
		(property "Footprint" "antmicro-footprints:R_0402_1005Metric"
			(at 12.7 109.22 0)
			(effects
				(font
					(size 1.27 1.27)
					(thickness 0.15)
				)
				(justify left bottom)
				(hide yes)
			)
		)
		(property "Datasheet" "https://www.bourns.com/docs/product-datasheets/cr.pdf"
			(at 10.16 109.22 0)
			(effects
				(font
					(size 1.27 1.27)
					(thickness 0.15)
				)
				(justify left bottom)
				(hide yes)
			)
		)
		(property "Description" "SMD Chip Resistor, 10 kohm, ± 1%, 62.5 mW, 0402 [1005 Metric], Thick Film, General Purpose"
			(at 27.94 88.9 0)
			(effects
				(font
					(size 1.27 1.27)
				)
				(hide yes)
			)
		)
		(property "MPN" "CR0402-FX-1002GLF"
			(at 7.62 109.22 0)
			(effects
				(font
					(size 1.27 1.27)
					(thickness 0.15)
				)
				(justify left bottom)
				(hide yes)
			)
		)
		(property "Manufacturer" "Bourns"
			(at 5.08 109.22 0)
			(effects
				(font
					(size 1.27 1.27)
					(thickness 0.15)
				)
				(justify left bottom)
				(hide yes)
			)
		)
		(property "License" "Apache-2.0"
			(at 2.54 109.22 0)
			(effects
				(font
					(size 1.27 1.27)
					(thickness 0.15)
				)
				(justify left bottom)
				(hide yes)
			)
		)
		(property "Author" "Antmicro"
			(at 0 109.22 0)
			(effects
				(font
					(size 1.27 1.27)
					(thickness 0.15)
				)
				(justify left bottom)
				(hide yes)
			)
		)
		(property "Val" "10k"
			(at 33.274 92.456 90)
			(effects
				(font
					(size 1.27 1.27)
					(thickness 0.15)
				)
				(justify right)
			)
		)
		(property "Tolerance" "1%"
			(at 17.78 109.22 0)
			(effects
				(font
					(size 1.27 1.27)
				)
				(justify left bottom)
				(hide yes)
			)
		)
		(pin "2"
		)
		(pin "1"
		)
		(instances
			(project "jetson-agx-thor-baseboard"
				(path ""
					(reference "R67")
					(unit 1)
				)
			)
		)
	)
	(symbol
		(lib_id "antmicropower:GND")
		(at 337.82 43.18 0)
		(unit 1)
		(exclude_from_sim no)
		(in_bom yes)
		(on_board yes)
		(dnp no)
		(property "Reference" "#PWR0172"
			(at 337.82 49.53 0)
			(effects
				(font
					(size 1.27 1.27)
				)
				(justify left bottom)
				(hide yes)
			)
		)
		(property "Value" "GND"
			(at 337.82 46.99 0)
			(effects
				(font
					(size 1.27 1.27)
					(thickness 0.15)
				)
			)
		)
		(property "Footprint" ""
			(at 346.71 50.8 0)
			(effects
				(font
					(size 1.27 1.27)
					(thickness 0.15)
				)
				(justify left bottom)
				(hide yes)
			)
		)
		(property "Datasheet" ""
			(at 346.71 55.88 0)
			(effects
				(font
					(size 1.27 1.27)
					(thickness 0.15)
				)
				(justify left bottom)
				(hide yes)
			)
		)
		(property "Description" ""
			(at 337.82 43.18 0)
			(effects
				(font
					(size 1.27 1.27)
				)
				(hide yes)
			)
		)
		(property "Author" "Antmicro"
			(at 346.71 50.8 0)
			(effects
				(font
					(size 1.27 1.27)
					(thickness 0.15)
				)
				(justify left bottom)
				(hide yes)
			)
		)
		(property "License" "Apache-2.0"
			(at 346.71 53.34 0)
			(effects
				(font
					(size 1.27 1.27)
					(thickness 0.15)
				)
				(justify left bottom)
				(hide yes)
			)
		)
		(pin "1"
		)
		(instances
			(project "jetson-agx-thor-baseboard"
				(path ""
					(reference "#PWR0172")
					(unit 1)
				)
			)
		)
	)
	(symbol
		(lib_id "antmicroResistors0402:R_0R_0402")
		(at 187.96 143.51 0)
		(unit 1)
		(exclude_from_sim no)
		(in_bom yes)
		(on_board yes)
		(dnp no)
		(property "Reference" "R58"
			(at 193.04 142.875 0)
			(effects
				(font
					(size 1.27 1.27)
				)
				(justify left bottom)
			)
		)
		(property "Value" "R_0R_0402"
			(at 208.28 156.21 0)
			(effects
				(font
					(size 1.27 1.27)
					(thickness 0.15)
				)
				(justify left bottom)
				(hide yes)
			)
		)
		(property "Footprint" "antmicro-footprints:R_0402_1005Metric"
			(at 208.28 158.75 0)
			(effects
				(font
					(size 1.27 1.27)
					(thickness 0.15)
				)
				(justify left bottom)
				(hide yes)
			)
		)
		(property "Datasheet" "https://industrial.panasonic.com/cdbs/www-data/pdf/RDA0000/AOA0000C301.pdf"
			(at 208.28 161.29 0)
			(effects
				(font
					(size 1.27 1.27)
					(thickness 0.15)
				)
				(justify left bottom)
				(hide yes)
			)
		)
		(property "Description" "SMD Chip Resistor, Jumper, 0 ohm, 100 mW, 0402 [1005 Metric], Thick Film, General Purpose"
			(at 187.96 143.51 0)
			(effects
				(font
					(size 1.27 1.27)
				)
				(hide yes)
			)
		)
		(property "Manufacturer" "Panasonic"
			(at 208.28 166.37 0)
			(effects
				(font
					(size 1.27 1.27)
					(thickness 0.15)
				)
				(justify left bottom)
				(hide yes)
			)
		)
		(property "MPN" "ERJ2GE0R00X"
			(at 208.28 163.83 0)
			(effects
				(font
					(size 1.27 1.27)
					(thickness 0.15)
				)
				(justify left bottom)
				(hide yes)
			)
		)
		(property "Val" "0R"
			(at 185.42 142.875 0)
			(effects
				(font
					(size 1.27 1.27)
					(thickness 0.15)
				)
				(justify left bottom)
			)
		)
		(property "License" "Apache-2.0"
			(at 208.28 168.91 0)
			(effects
				(font
					(size 1.27 1.27)
					(thickness 0.15)
				)
				(justify left bottom)
				(hide yes)
			)
		)
		(property "Author" "Antmicro"
			(at 208.28 171.45 0)
			(effects
				(font
					(size 1.27 1.27)
					(thickness 0.15)
				)
				(justify left bottom)
				(hide yes)
			)
		)
		(property "Tolerance" "~"
			(at 208.28 153.67 0)
			(effects
				(font
					(size 1.27 1.27)
				)
				(justify left bottom)
				(hide yes)
			)
		)
		(property "Current" "1A"
			(at 208.28 173.99 0)
			(effects
				(font
					(size 1.27 1.27)
					(thickness 0.15)
				)
				(justify left bottom)
				(hide yes)
			)
		)
		(pin "1"
		)
		(pin "2"
		)
		(instances
			(project "jetson-agx-thor-baseboard"
				(path ""
					(reference "R58")
					(unit 1)
				)
			)
		)
	)
	(symbol
		(lib_id "antmicroMemory:SST26VF064B")
		(at 92.71 233.68 0)
		(unit 1)
		(exclude_from_sim no)
		(in_bom no)
		(on_board yes)
		(dnp yes)
		(property "Reference" "U52"
			(at 94.742 226.06 0)
			(effects
				(font
					(size 1.27 1.27)
					(thickness 0.15)
				)
				(justify left)
			)
		)
		(property "Value" "SST26VF064B"
			(at 128.27 241.3 0)
			(effects
				(font
					(size 1.27 1.27)
					(thickness 0.15)
				)
				(justify left bottom)
				(hide yes)
			)
		)
		(property "Footprint" "antmicro-footprints:SOIJ-8_5.28x5.28x2.0mm_P1.27mm"
			(at 128.27 243.84 0)
			(effects
				(font
					(size 1.27 1.27)
					(thickness 0.15)
				)
				(justify left bottom)
				(hide yes)
			)
		)
		(property "Datasheet" "https://www.mouser.com/datasheet/3/282/1/SST26VF064B-SST26VF064BA-2-5V-3-0V-64-Mbit-Serial-Quad-IO--SQI--Flash-Memory-20005119K.pdf"
			(at 128.27 246.38 0)
			(effects
				(font
					(size 1.27 1.27)
					(thickness 0.15)
				)
				(justify left bottom)
				(hide yes)
			)
		)
		(property "Description" "64-Mbit 2.3V-3.6V, SQI Flash Memory, -40°C to +85°C"
			(at 128.27 256.54 0)
			(effects
				(font
					(size 1.27 1.27)
				)
				(justify left bottom)
				(hide yes)
			)
		)
		(property "MPN" "SST26VF064B-104I/SM"
			(at 94.742 228.6 0)
			(effects
				(font
					(size 1.27 1.27)
					(thickness 0.15)
				)
				(justify left)
			)
		)
		(property "Manufacturer" "Microchip Technology"
			(at 128.27 248.92 0)
			(effects
				(font
					(size 1.27 1.27)
					(thickness 0.15)
				)
				(justify left bottom)
				(hide yes)
			)
		)
		(property "Author" "Antmicro"
			(at 128.27 251.46 0)
			(effects
				(font
					(size 1.27 1.27)
					(thickness 0.15)
				)
				(justify left bottom)
				(hide yes)
			)
		)
		(property "License" "Apache-2.0"
			(at 128.27 254 0)
			(effects
				(font
					(size 1.27 1.27)
					(thickness 0.15)
				)
				(justify left bottom)
				(hide yes)
			)
		)
		(pin "3"
		)
		(pin "7"
		)
		(pin "8"
		)
		(pin "4"
		)
		(pin "6"
		)
		(pin "1"
		)
		(pin "5"
		)
		(pin "2"
		)
		(instances
			(project ""
				(path ""
					(reference "U52")
					(unit 1)
				)
			)
		)
	)
	(symbol
		(lib_id "antmicroResistors0402:R_10k_0402")
		(at 167.64 260.35 270)
		(unit 1)
		(exclude_from_sim no)
		(in_bom yes)
		(on_board yes)
		(dnp no)
		(property "Reference" "R329"
			(at 173.99 261.62 90)
			(effects
				(font
					(size 1.27 1.27)
					(thickness 0.15)
				)
				(justify right)
			)
		)
		(property "Value" "R_10k_0402"
			(at 154.94 280.67 0)
			(effects
				(font
					(size 1.27 1.27)
					(thickness 0.15)
				)
				(justify left bottom)
				(hide yes)
			)
		)
		(property "Footprint" "antmicro-footprints:R_0402_1005Metric"
			(at 152.4 280.67 0)
			(effects
				(font
					(size 1.27 1.27)
					(thickness 0.15)
				)
				(justify left bottom)
				(hide yes)
			)
		)
		(property "Datasheet" "https://www.bourns.com/docs/product-datasheets/cr.pdf"
			(at 149.86 280.67 0)
			(effects
				(font
					(size 1.27 1.27)
					(thickness 0.15)
				)
				(justify left bottom)
				(hide yes)
			)
		)
		(property "Description" "SMD Chip Resistor, 10 kohm, ± 1%, 62.5 mW, 0402 [1005 Metric], Thick Film, General Purpose"
			(at 167.64 260.35 0)
			(effects
				(font
					(size 1.27 1.27)
				)
				(hide yes)
			)
		)
		(property "MPN" "CR0402-FX-1002GLF"
			(at 147.32 280.67 0)
			(effects
				(font
					(size 1.27 1.27)
					(thickness 0.15)
				)
				(justify left bottom)
				(hide yes)
			)
		)
		(property "Manufacturer" "Bourns"
			(at 144.78 280.67 0)
			(effects
				(font
					(size 1.27 1.27)
					(thickness 0.15)
				)
				(justify left bottom)
				(hide yes)
			)
		)
		(property "License" "Apache-2.0"
			(at 142.24 280.67 0)
			(effects
				(font
					(size 1.27 1.27)
					(thickness 0.15)
				)
				(justify left bottom)
				(hide yes)
			)
		)
		(property "Author" "Antmicro"
			(at 139.7 280.67 0)
			(effects
				(font
					(size 1.27 1.27)
					(thickness 0.15)
				)
				(justify left bottom)
				(hide yes)
			)
		)
		(property "Val" "10k"
			(at 172.72 264.16 90)
			(effects
				(font
					(size 1.27 1.27)
					(thickness 0.15)
				)
				(justify right)
			)
		)
		(property "Tolerance" "1%"
			(at 157.48 280.67 0)
			(effects
				(font
					(size 1.27 1.27)
				)
				(justify left bottom)
				(hide yes)
			)
		)
		(pin "2"
		)
		(pin "1"
		)
		(instances
			(project "jetson-agx-thor-baseboard"
				(path ""
					(reference "R329")
					(unit 1)
				)
			)
		)
	)
	(symbol
		(lib_id "antmicropower:GND")
		(at 336.55 165.1 0)
		(unit 1)
		(exclude_from_sim no)
		(in_bom yes)
		(on_board yes)
		(dnp no)
		(property "Reference" "#PWR0207"
			(at 336.55 171.45 0)
			(effects
				(font
					(size 1.27 1.27)
				)
				(justify left bottom)
				(hide yes)
			)
		)
		(property "Value" "GND"
			(at 336.55 168.91 0)
			(effects
				(font
					(size 1.27 1.27)
					(thickness 0.15)
				)
			)
		)
		(property "Footprint" ""
			(at 345.44 172.72 0)
			(effects
				(font
					(size 1.27 1.27)
					(thickness 0.15)
				)
				(justify left bottom)
				(hide yes)
			)
		)
		(property "Datasheet" ""
			(at 345.44 177.8 0)
			(effects
				(font
					(size 1.27 1.27)
					(thickness 0.15)
				)
				(justify left bottom)
				(hide yes)
			)
		)
		(property "Description" ""
			(at 336.55 165.1 0)
			(effects
				(font
					(size 1.27 1.27)
				)
				(hide yes)
			)
		)
		(property "Author" "Antmicro"
			(at 345.44 172.72 0)
			(effects
				(font
					(size 1.27 1.27)
					(thickness 0.15)
				)
				(justify left bottom)
				(hide yes)
			)
		)
		(property "License" "Apache-2.0"
			(at 345.44 175.26 0)
			(effects
				(font
					(size 1.27 1.27)
					(thickness 0.15)
				)
				(justify left bottom)
				(hide yes)
			)
		)
		(pin "1"
		)
		(instances
			(project "jetson-agx-thor-baseboard"
				(path ""
					(reference "#PWR0207")
					(unit 1)
				)
			)
		)
	)
	(symbol
		(lib_id "antmicroResistors0402:R_10k_0402")
		(at 167.64 236.22 270)
		(unit 1)
		(exclude_from_sim no)
		(in_bom yes)
		(on_board yes)
		(dnp no)
		(property "Reference" "R328"
			(at 173.99 237.49 90)
			(effects
				(font
					(size 1.27 1.27)
					(thickness 0.15)
				)
				(justify right)
			)
		)
		(property "Value" "R_10k_0402"
			(at 154.94 256.54 0)
			(effects
				(font
					(size 1.27 1.27)
					(thickness 0.15)
				)
				(justify left bottom)
				(hide yes)
			)
		)
		(property "Footprint" "antmicro-footprints:R_0402_1005Metric"
			(at 152.4 256.54 0)
			(effects
				(font
					(size 1.27 1.27)
					(thickness 0.15)
				)
				(justify left bottom)
				(hide yes)
			)
		)
		(property "Datasheet" "https://www.bourns.com/docs/product-datasheets/cr.pdf"
			(at 149.86 256.54 0)
			(effects
				(font
					(size 1.27 1.27)
					(thickness 0.15)
				)
				(justify left bottom)
				(hide yes)
			)
		)
		(property "Description" "SMD Chip Resistor, 10 kohm, ± 1%, 62.5 mW, 0402 [1005 Metric], Thick Film, General Purpose"
			(at 167.64 236.22 0)
			(effects
				(font
					(size 1.27 1.27)
				)
				(hide yes)
			)
		)
		(property "MPN" "CR0402-FX-1002GLF"
			(at 147.32 256.54 0)
			(effects
				(font
					(size 1.27 1.27)
					(thickness 0.15)
				)
				(justify left bottom)
				(hide yes)
			)
		)
		(property "Manufacturer" "Bourns"
			(at 144.78 256.54 0)
			(effects
				(font
					(size 1.27 1.27)
					(thickness 0.15)
				)
				(justify left bottom)
				(hide yes)
			)
		)
		(property "License" "Apache-2.0"
			(at 142.24 256.54 0)
			(effects
				(font
					(size 1.27 1.27)
					(thickness 0.15)
				)
				(justify left bottom)
				(hide yes)
			)
		)
		(property "Author" "Antmicro"
			(at 139.7 256.54 0)
			(effects
				(font
					(size 1.27 1.27)
					(thickness 0.15)
				)
				(justify left bottom)
				(hide yes)
			)
		)
		(property "Val" "10k"
			(at 172.72 240.03 90)
			(effects
				(font
					(size 1.27 1.27)
					(thickness 0.15)
				)
				(justify right)
			)
		)
		(property "Tolerance" "1%"
			(at 157.48 256.54 0)
			(effects
				(font
					(size 1.27 1.27)
				)
				(justify left bottom)
				(hide yes)
			)
		)
		(pin "2"
		)
		(pin "1"
		)
		(instances
			(project "jetson-agx-thor-baseboard"
				(path ""
					(reference "R328")
					(unit 1)
				)
			)
		)
	)
	(symbol
		(lib_id "antmicropower:GND")
		(at 361.95 39.37 0)
		(unit 1)
		(exclude_from_sim no)
		(in_bom yes)
		(on_board yes)
		(dnp no)
		(property "Reference" "#PWR0174"
			(at 361.95 45.72 0)
			(effects
				(font
					(size 1.27 1.27)
				)
				(justify left bottom)
				(hide yes)
			)
		)
		(property "Value" "GND"
			(at 361.95 43.18 0)
			(effects
				(font
					(size 1.27 1.27)
					(thickness 0.15)
				)
			)
		)
		(property "Footprint" ""
			(at 370.84 46.99 0)
			(effects
				(font
					(size 1.27 1.27)
					(thickness 0.15)
				)
				(justify left bottom)
				(hide yes)
			)
		)
		(property "Datasheet" ""
			(at 370.84 52.07 0)
			(effects
				(font
					(size 1.27 1.27)
					(thickness 0.15)
				)
				(justify left bottom)
				(hide yes)
			)
		)
		(property "Description" ""
			(at 361.95 39.37 0)
			(effects
				(font
					(size 1.27 1.27)
				)
				(hide yes)
			)
		)
		(property "Author" "Antmicro"
			(at 370.84 46.99 0)
			(effects
				(font
					(size 1.27 1.27)
					(thickness 0.15)
				)
				(justify left bottom)
				(hide yes)
			)
		)
		(property "License" "Apache-2.0"
			(at 370.84 49.53 0)
			(effects
				(font
					(size 1.27 1.27)
					(thickness 0.15)
				)
				(justify left bottom)
				(hide yes)
			)
		)
		(pin "1"
		)
		(instances
			(project "jetson-agx-thor-baseboard"
				(path ""
					(reference "#PWR0174")
					(unit 1)
				)
			)
		)
	)
	(symbol
		(lib_id "antmicroResistors0402:R_0R_0402")
		(at 187.96 146.05 0)
		(unit 1)
		(exclude_from_sim no)
		(in_bom yes)
		(on_board yes)
		(dnp no)
		(property "Reference" "R62"
			(at 193.04 145.415 0)
			(effects
				(font
					(size 1.27 1.27)
				)
				(justify left bottom)
			)
		)
		(property "Value" "R_0R_0402"
			(at 208.28 158.75 0)
			(effects
				(font
					(size 1.27 1.27)
					(thickness 0.15)
				)
				(justify left bottom)
				(hide yes)
			)
		)
		(property "Footprint" "antmicro-footprints:R_0402_1005Metric"
			(at 208.28 161.29 0)
			(effects
				(font
					(size 1.27 1.27)
					(thickness 0.15)
				)
				(justify left bottom)
				(hide yes)
			)
		)
		(property "Datasheet" "https://industrial.panasonic.com/cdbs/www-data/pdf/RDA0000/AOA0000C301.pdf"
			(at 208.28 163.83 0)
			(effects
				(font
					(size 1.27 1.27)
					(thickness 0.15)
				)
				(justify left bottom)
				(hide yes)
			)
		)
		(property "Description" "SMD Chip Resistor, Jumper, 0 ohm, 100 mW, 0402 [1005 Metric], Thick Film, General Purpose"
			(at 187.96 146.05 0)
			(effects
				(font
					(size 1.27 1.27)
				)
				(hide yes)
			)
		)
		(property "Manufacturer" "Panasonic"
			(at 208.28 168.91 0)
			(effects
				(font
					(size 1.27 1.27)
					(thickness 0.15)
				)
				(justify left bottom)
				(hide yes)
			)
		)
		(property "MPN" "ERJ2GE0R00X"
			(at 208.28 166.37 0)
			(effects
				(font
					(size 1.27 1.27)
					(thickness 0.15)
				)
				(justify left bottom)
				(hide yes)
			)
		)
		(property "Val" "0R"
			(at 185.42 145.415 0)
			(effects
				(font
					(size 1.27 1.27)
					(thickness 0.15)
				)
				(justify left bottom)
			)
		)
		(property "License" "Apache-2.0"
			(at 208.28 171.45 0)
			(effects
				(font
					(size 1.27 1.27)
					(thickness 0.15)
				)
				(justify left bottom)
				(hide yes)
			)
		)
		(property "Author" "Antmicro"
			(at 208.28 173.99 0)
			(effects
				(font
					(size 1.27 1.27)
					(thickness 0.15)
				)
				(justify left bottom)
				(hide yes)
			)
		)
		(property "Tolerance" "~"
			(at 208.28 156.21 0)
			(effects
				(font
					(size 1.27 1.27)
				)
				(justify left bottom)
				(hide yes)
			)
		)
		(property "Current" "1A"
			(at 208.28 176.53 0)
			(effects
				(font
					(size 1.27 1.27)
					(thickness 0.15)
				)
				(justify left bottom)
				(hide yes)
			)
		)
		(pin "1"
		)
		(pin "2"
		)
		(instances
			(project "jetson-agx-thor-baseboard"
				(path ""
					(reference "R62")
					(unit 1)
				)
			)
		)
	)
	(symbol
		(lib_id "antmicropower:GND")
		(at 27.94 137.16 0)
		(mirror y)
		(unit 1)
		(exclude_from_sim no)
		(in_bom yes)
		(on_board yes)
		(dnp no)
		(property "Reference" "#PWR0508"
			(at 27.94 143.51 0)
			(effects
				(font
					(size 1.27 1.27)
				)
				(justify left bottom)
				(hide yes)
			)
		)
		(property "Value" "GND"
			(at 27.94 140.97 0)
			(effects
				(font
					(size 1.27 1.27)
					(thickness 0.15)
				)
			)
		)
		(property "Footprint" ""
			(at 19.05 144.78 0)
			(effects
				(font
					(size 1.27 1.27)
					(thickness 0.15)
				)
				(justify left bottom)
				(hide yes)
			)
		)
		(property "Datasheet" ""
			(at 19.05 149.86 0)
			(effects
				(font
					(size 1.27 1.27)
					(thickness 0.15)
				)
				(justify left bottom)
				(hide yes)
			)
		)
		(property "Description" ""
			(at 27.94 137.16 0)
			(effects
				(font
					(size 1.27 1.27)
				)
				(hide yes)
			)
		)
		(property "Author" "Antmicro"
			(at 19.05 144.78 0)
			(effects
				(font
					(size 1.27 1.27)
					(thickness 0.15)
				)
				(justify left bottom)
				(hide yes)
			)
		)
		(property "License" "Apache-2.0"
			(at 19.05 147.32 0)
			(effects
				(font
					(size 1.27 1.27)
					(thickness 0.15)
				)
				(justify left bottom)
				(hide yes)
			)
		)
		(pin "1"
		)
		(instances
			(project "jetson-agx-thor-baseboard"
				(path ""
					(reference "#PWR0508")
					(unit 1)
				)
			)
		)
	)
	(symbol
		(lib_id "antmicropower:GND")
		(at 393.7 45.72 0)
		(unit 1)
		(exclude_from_sim no)
		(in_bom yes)
		(on_board yes)
		(dnp no)
		(property "Reference" "#PWR0179"
			(at 393.7 52.07 0)
			(effects
				(font
					(size 1.27 1.27)
				)
				(justify left bottom)
				(hide yes)
			)
		)
		(property "Value" "GND"
			(at 393.7 49.53 0)
			(effects
				(font
					(size 1.27 1.27)
					(thickness 0.15)
				)
			)
		)
		(property "Footprint" ""
			(at 402.59 53.34 0)
			(effects
				(font
					(size 1.27 1.27)
					(thickness 0.15)
				)
				(justify left bottom)
				(hide yes)
			)
		)
		(property "Datasheet" ""
			(at 402.59 58.42 0)
			(effects
				(font
					(size 1.27 1.27)
					(thickness 0.15)
				)
				(justify left bottom)
				(hide yes)
			)
		)
		(property "Description" ""
			(at 393.7 45.72 0)
			(effects
				(font
					(size 1.27 1.27)
				)
				(hide yes)
			)
		)
		(property "Author" "Antmicro"
			(at 402.59 53.34 0)
			(effects
				(font
					(size 1.27 1.27)
					(thickness 0.15)
				)
				(justify left bottom)
				(hide yes)
			)
		)
		(property "License" "Apache-2.0"
			(at 402.59 55.88 0)
			(effects
				(font
					(size 1.27 1.27)
					(thickness 0.15)
				)
				(justify left bottom)
				(hide yes)
			)
		)
		(pin "1"
		)
		(instances
			(project "jetson-agx-thor-baseboard"
				(path ""
					(reference "#PWR0179")
					(unit 1)
				)
			)
		)
	)
	(symbol
		(lib_id "antmicropower:+5V")
		(at 307.34 142.24 0)
		(unit 1)
		(exclude_from_sim no)
		(in_bom yes)
		(on_board yes)
		(dnp no)
		(property "Reference" "#PWR0185"
			(at 307.34 146.05 0)
			(effects
				(font
					(size 1.27 1.27)
				)
				(justify left bottom)
				(hide yes)
			)
		)
		(property "Value" "+5V"
			(at 305.435 139.065 0)
			(effects
				(font
					(size 1.27 1.27)
					(thickness 0.15)
				)
				(justify left bottom)
			)
		)
		(property "Footprint" ""
			(at 322.58 149.86 0)
			(effects
				(font
					(size 1.27 1.27)
					(thickness 0.15)
				)
				(justify left bottom)
				(hide yes)
			)
		)
		(property "Datasheet" ""
			(at 322.58 152.4 0)
			(effects
				(font
					(size 1.27 1.27)
					(thickness 0.15)
				)
				(justify left bottom)
				(hide yes)
			)
		)
		(property "Description" ""
			(at 307.34 142.24 0)
			(effects
				(font
					(size 1.27 1.27)
				)
				(hide yes)
			)
		)
		(property "Author" "Antmicro"
			(at 322.58 149.86 0)
			(effects
				(font
					(size 1.27 1.27)
					(thickness 0.15)
				)
				(justify left bottom)
				(hide yes)
			)
		)
		(property "License" "Apache-2.0"
			(at 322.58 152.4 0)
			(effects
				(font
					(size 1.27 1.27)
					(thickness 0.15)
				)
				(justify left bottom)
				(hide yes)
			)
		)
		(pin "1"
		)
		(instances
			(project "jetson-agx-thor-baseboard"
				(path ""
					(reference "#PWR0185")
					(unit 1)
				)
			)
		)
	)
	(symbol
		(lib_id "antmicroCapacitors0402:C_100n_0402")
		(at 96.52 74.93 0)
		(mirror x)
		(unit 1)
		(exclude_from_sim no)
		(in_bom yes)
		(on_board yes)
		(dnp no)
		(property "Reference" "C253"
			(at 105.41 73.66 0)
			(effects
				(font
					(size 1.27 1.27)
				)
			)
		)
		(property "Value" "C_100n_0402"
			(at 116.84 64.77 0)
			(effects
				(font
					(size 1.27 1.27)
					(thickness 0.15)
				)
				(justify left bottom)
				(hide yes)
			)
		)
		(property "Footprint" "antmicro-footprints:C_0402_1005Metric"
			(at 116.84 62.23 0)
			(effects
				(font
					(size 1.27 1.27)
					(thickness 0.15)
				)
				(justify left bottom)
				(hide yes)
			)
		)
		(property "Datasheet" "https://www.murata.com/products/productdetail?partno=GRM155R61H104KE14%23"
			(at 116.84 59.69 0)
			(effects
				(font
					(size 1.27 1.27)
					(thickness 0.15)
				)
				(justify left bottom)
				(hide yes)
			)
		)
		(property "Description" "SMD Multilayer Ceramic Capacitor, 0.1 µF, 50 V, 0402 [1005 Metric], ± 10%, X5R, GRM Series"
			(at 96.52 74.93 0)
			(effects
				(font
					(size 1.27 1.27)
				)
				(hide yes)
			)
		)
		(property "Manufacturer" "Murata"
			(at 116.84 54.61 0)
			(effects
				(font
					(size 1.27 1.27)
					(thickness 0.15)
				)
				(justify left bottom)
				(hide yes)
			)
		)
		(property "MPN" "GRM155R61H104KE14D"
			(at 116.84 57.15 0)
			(effects
				(font
					(size 1.27 1.27)
					(thickness 0.15)
				)
				(justify left bottom)
				(hide yes)
			)
		)
		(property "Val" "100n"
			(at 95.758 73.914 0)
			(effects
				(font
					(size 1.27 1.27)
					(thickness 0.15)
				)
			)
		)
		(property "License" "Apache-2.0"
			(at 116.84 52.07 0)
			(effects
				(font
					(size 1.27 1.27)
					(thickness 0.15)
				)
				(justify left bottom)
				(hide yes)
			)
		)
		(property "Author" "Antmicro"
			(at 116.84 49.53 0)
			(effects
				(font
					(size 1.27 1.27)
					(thickness 0.15)
				)
				(justify left bottom)
				(hide yes)
			)
		)
		(property "Voltage" "50V"
			(at 116.84 46.99 0)
			(effects
				(font
					(size 1.27 1.27)
				)
				(justify left bottom)
				(hide yes)
			)
		)
		(property "Dielectric" "X5R"
			(at 116.84 44.45 0)
			(effects
				(font
					(size 1.27 1.27)
				)
				(justify left bottom)
				(hide yes)
			)
		)
		(pin "1"
		)
		(pin "2"
		)
		(instances
			(project "jetson-agx-thor-baseboard"
				(path ""
					(reference "C253")
					(unit 1)
				)
			)
		)
	)
	(symbol
		(lib_id "antmicroCapacitors0402:C_100n_0402")
		(at 48.26 66.04 90)
		(unit 1)
		(exclude_from_sim no)
		(in_bom yes)
		(on_board yes)
		(dnp no)
		(fields_autoplaced yes)
		(property "Reference" "C85"
			(at 50.8 62.2236 90)
			(effects
				(font
					(size 1.27 1.27)
					(thickness 0.15)
				)
				(justify right)
			)
		)
		(property "Value" "C_100n_0402"
			(at 71.12 50.8 0)
			(effects
				(font
					(size 1.27 1.27)
					(thickness 0.15)
				)
				(justify left bottom)
				(hide yes)
			)
		)
		(property "Footprint" "antmicro-footprints:C_0402_1005Metric"
			(at 73.66 50.8 0)
			(effects
				(font
					(size 1.27 1.27)
					(thickness 0.15)
				)
				(justify left bottom)
				(hide yes)
			)
		)
		(property "Datasheet" "https://www.murata.com/products/productdetail?partno=GRM155R61H104KE14%23"
			(at 76.2 50.8 0)
			(effects
				(font
					(size 1.27 1.27)
					(thickness 0.15)
				)
				(justify left bottom)
				(hide yes)
			)
		)
		(property "Description" "SMD Multilayer Ceramic Capacitor, 0.1 µF, 50 V, 0402 [1005 Metric], ± 10%, X5R, GRM Series"
			(at 48.26 66.04 0)
			(effects
				(font
					(size 1.27 1.27)
				)
				(hide yes)
			)
		)
		(property "MPN" "GRM155R61H104KE14D"
			(at 78.74 50.8 0)
			(effects
				(font
					(size 1.27 1.27)
					(thickness 0.15)
				)
				(justify left bottom)
				(hide yes)
			)
		)
		(property "Val" "100n"
			(at 50.8 64.7636 90)
			(effects
				(font
					(size 1.27 1.27)
					(thickness 0.15)
				)
				(justify right)
			)
		)
		(property "Voltage" "50V"
			(at 58.42 50.8 0)
			(effects
				(font
					(size 1.27 1.27)
					(thickness 0.15)
				)
				(justify left bottom)
				(hide yes)
			)
		)
		(property "Dielectric" "X5R"
			(at 60.96 50.8 0)
			(effects
				(font
					(size 1.27 1.27)
					(thickness 0.15)
				)
				(justify left bottom)
				(hide yes)
			)
		)
		(property "Manufacturer" "Murata"
			(at 63.5 50.8 0)
			(effects
				(font
					(size 1.27 1.27)
					(thickness 0.15)
				)
				(justify left bottom)
				(hide yes)
			)
		)
		(property "License" "Apache-2.0"
			(at 66.04 50.8 0)
			(effects
				(font
					(size 1.27 1.27)
					(thickness 0.15)
				)
				(justify left bottom)
				(hide yes)
			)
		)
		(property "Author" "Antmicro"
			(at 68.58 50.8 0)
			(effects
				(font
					(size 1.27 1.27)
					(thickness 0.15)
				)
				(justify left bottom)
				(hide yes)
			)
		)
		(pin "1"
		)
		(pin "2"
		)
		(instances
			(project "jetson-agx-thor-baseboard"
				(path ""
					(reference "C85")
					(unit 1)
				)
			)
		)
	)
	(symbol
		(lib_id "antmicropower:GND")
		(at 213.36 196.85 0)
		(unit 1)
		(exclude_from_sim no)
		(in_bom yes)
		(on_board yes)
		(dnp no)
		(property "Reference" "#PWR0517"
			(at 213.36 203.2 0)
			(effects
				(font
					(size 1.27 1.27)
				)
				(justify left bottom)
				(hide yes)
			)
		)
		(property "Value" "GND"
			(at 213.36 200.66 0)
			(effects
				(font
					(size 1.27 1.27)
					(thickness 0.15)
				)
			)
		)
		(property "Footprint" ""
			(at 222.25 204.47 0)
			(effects
				(font
					(size 1.27 1.27)
					(thickness 0.15)
				)
				(justify left bottom)
				(hide yes)
			)
		)
		(property "Datasheet" ""
			(at 222.25 209.55 0)
			(effects
				(font
					(size 1.27 1.27)
					(thickness 0.15)
				)
				(justify left bottom)
				(hide yes)
			)
		)
		(property "Description" ""
			(at 213.36 196.85 0)
			(effects
				(font
					(size 1.27 1.27)
				)
				(hide yes)
			)
		)
		(property "Author" "Antmicro"
			(at 222.25 204.47 0)
			(effects
				(font
					(size 1.27 1.27)
					(thickness 0.15)
				)
				(justify left bottom)
				(hide yes)
			)
		)
		(property "License" "Apache-2.0"
			(at 222.25 207.01 0)
			(effects
				(font
					(size 1.27 1.27)
					(thickness 0.15)
				)
				(justify left bottom)
				(hide yes)
			)
		)
		(pin "1"
		)
		(instances
			(project "jetson-agx-thor-baseboard"
				(path ""
					(reference "#PWR0517")
					(unit 1)
				)
			)
		)
	)
	(symbol
		(lib_id "antmicropower:GND")
		(at 307.34 149.86 0)
		(unit 1)
		(exclude_from_sim no)
		(in_bom yes)
		(on_board yes)
		(dnp no)
		(property "Reference" "#PWR0186"
			(at 307.34 156.21 0)
			(effects
				(font
					(size 1.27 1.27)
				)
				(justify left bottom)
				(hide yes)
			)
		)
		(property "Value" "GND"
			(at 307.34 153.67 0)
			(effects
				(font
					(size 1.27 1.27)
					(thickness 0.15)
				)
			)
		)
		(property "Footprint" ""
			(at 316.23 157.48 0)
			(effects
				(font
					(size 1.27 1.27)
					(thickness 0.15)
				)
				(justify left bottom)
				(hide yes)
			)
		)
		(property "Datasheet" ""
			(at 316.23 162.56 0)
			(effects
				(font
					(size 1.27 1.27)
					(thickness 0.15)
				)
				(justify left bottom)
				(hide yes)
			)
		)
		(property "Description" ""
			(at 307.34 149.86 0)
			(effects
				(font
					(size 1.27 1.27)
				)
				(hide yes)
			)
		)
		(property "Author" "Antmicro"
			(at 316.23 157.48 0)
			(effects
				(font
					(size 1.27 1.27)
					(thickness 0.15)
				)
				(justify left bottom)
				(hide yes)
			)
		)
		(property "License" "Apache-2.0"
			(at 316.23 160.02 0)
			(effects
				(font
					(size 1.27 1.27)
					(thickness 0.15)
				)
				(justify left bottom)
				(hide yes)
			)
		)
		(pin "1"
		)
		(instances
			(project "jetson-agx-thor-baseboard"
				(path ""
					(reference "#PWR0186")
					(unit 1)
				)
			)
		)
	)
	(symbol
		(lib_id "antmicroTVSDiodes:TPD4E05U06QDQARQ1")
		(at 322.58 53.34 270)
		(mirror x)
		(unit 1)
		(exclude_from_sim no)
		(in_bom yes)
		(on_board yes)
		(dnp no)
		(property "Reference" "U28"
			(at 315.976 40.132 90)
			(effects
				(font
					(size 1.27 1.27)
				)
				(justify left)
			)
		)
		(property "Value" "TPD4E05U06QDQARQ1"
			(at 312.42 29.21 0)
			(effects
				(font
					(size 1.27 1.27)
					(thickness 0.15)
				)
				(justify left bottom)
				(hide yes)
			)
		)
		(property "Footprint" "antmicro-footprints:USON-10_2.5x1mm_P0.5mm"
			(at 317.5 29.21 0)
			(effects
				(font
					(size 1.27 1.27)
					(thickness 0.15)
				)
				(justify left bottom)
				(hide yes)
			)
		)
		(property "Datasheet" "https://www.ti.com/lit/ds/symlink/tpd4e05u06-q1.pdf?HQS=dis-mous-null-mousermode-dsf-pf-null-wwe&ts=1663591265741&ref_url=https%253A%252F%252Fwww.mouser.com%252F"
			(at 314.96 29.21 0)
			(effects
				(font
					(size 1.27 1.27)
					(thickness 0.15)
				)
				(justify left bottom)
				(hide yes)
			)
		)
		(property "Description" "TVS diode array, 12 kV, USON-10, 5.5 V, 0.5 pF"
			(at 322.58 53.34 0)
			(effects
				(font
					(size 1.27 1.27)
				)
				(hide yes)
			)
		)
		(property "Manufacturer" "Texas Instruments"
			(at 309.88 29.21 0)
			(effects
				(font
					(size 1.27 1.27)
					(thickness 0.15)
				)
				(justify left bottom)
				(hide yes)
			)
		)
		(property "MPN" "TPD4E05U06QDQARQ1"
			(at 308.356 42.6721 90)
			(effects
				(font
					(size 1.27 1.27)
					(thickness 0.15)
				)
				(justify left)
			)
		)
		(property "Author" "Antmicro"
			(at 307.34 29.21 0)
			(effects
				(font
					(size 1.27 1.27)
					(thickness 0.15)
				)
				(justify left bottom)
				(hide yes)
			)
		)
		(property "License" "Apache-2.0"
			(at 304.8 29.21 0)
			(effects
				(font
					(size 1.27 1.27)
					(thickness 0.15)
				)
				(justify left bottom)
				(hide yes)
			)
		)
		(pin "1"
		)
		(pin "10"
		)
		(pin "2"
		)
		(pin "3"
		)
		(pin "4"
		)
		(pin "5"
		)
		(pin "6"
		)
		(pin "7"
		)
		(pin "8"
		)
		(pin "9"
		)
		(instances
			(project "jetson-agx-thor-baseboard"
				(path ""
					(reference "U28")
					(unit 1)
				)
			)
		)
	)
	(symbol
		(lib_id "antmicroResistors0402:R_0R_0402")
		(at 52.07 254 0)
		(unit 1)
		(exclude_from_sim no)
		(in_bom no)
		(on_board yes)
		(dnp yes)
		(property "Reference" "R379"
			(at 50.038 253.238 0)
			(effects
				(font
					(size 1.27 1.27)
					(thickness 0.15)
				)
			)
		)
		(property "Value" "R_0R_0402"
			(at 72.39 266.7 0)
			(effects
				(font
					(size 1.27 1.27)
					(thickness 0.15)
				)
				(justify left bottom)
				(hide yes)
			)
		)
		(property "Footprint" "antmicro-footprints:R_0402_1005Metric"
			(at 72.39 269.24 0)
			(effects
				(font
					(size 1.27 1.27)
					(thickness 0.15)
				)
				(justify left bottom)
				(hide yes)
			)
		)
		(property "Datasheet" "https://industrial.panasonic.com/cdbs/www-data/pdf/RDA0000/AOA0000C301.pdf"
			(at 72.39 271.78 0)
			(effects
				(font
					(size 1.27 1.27)
					(thickness 0.15)
				)
				(justify left bottom)
				(hide yes)
			)
		)
		(property "Description" "SMD Chip Resistor, Jumper, 0 ohm, 100 mW, 0402 [1005 Metric], Thick Film, General Purpose"
			(at 72.39 287.02 0)
			(effects
				(font
					(size 1.27 1.27)
				)
				(justify left bottom)
				(hide yes)
			)
		)
		(property "MPN" "ERJ2GE0R00X"
			(at 72.39 274.32 0)
			(effects
				(font
					(size 1.27 1.27)
					(thickness 0.15)
				)
				(justify left bottom)
				(hide yes)
			)
		)
		(property "Manufacturer" "Panasonic"
			(at 72.39 276.86 0)
			(effects
				(font
					(size 1.27 1.27)
					(thickness 0.15)
				)
				(justify left bottom)
				(hide yes)
			)
		)
		(property "License" "Apache-2.0"
			(at 72.39 279.4 0)
			(effects
				(font
					(size 1.27 1.27)
					(thickness 0.15)
				)
				(justify left bottom)
				(hide yes)
			)
		)
		(property "Author" "Antmicro"
			(at 72.39 281.94 0)
			(effects
				(font
					(size 1.27 1.27)
					(thickness 0.15)
				)
				(justify left bottom)
				(hide yes)
			)
		)
		(property "Val" "0R"
			(at 58.42 253.238 0)
			(effects
				(font
					(size 1.27 1.27)
					(thickness 0.15)
				)
			)
		)
		(property "Tolerance" "~"
			(at 72.39 264.16 0)
			(effects
				(font
					(size 1.27 1.27)
				)
				(justify left bottom)
				(hide yes)
			)
		)
		(property "Current" "1A"
			(at 72.39 284.48 0)
			(effects
				(font
					(size 1.27 1.27)
					(thickness 0.15)
				)
				(justify left bottom)
				(hide yes)
			)
		)
		(pin "1"
		)
		(pin "2"
		)
		(instances
			(project "jetson-agx-thor-baseboard"
				(path ""
					(reference "R379")
					(unit 1)
				)
			)
		)
	)
	(symbol
		(lib_id "antmicropower:+3V3")
		(at 27.94 176.53 0)
		(unit 1)
		(exclude_from_sim no)
		(in_bom yes)
		(on_board yes)
		(dnp no)
		(property "Reference" "#PWR0470"
			(at 43.18 176.53 0)
			(effects
				(font
					(size 1.27 1.27)
					(thickness 0.15)
				)
				(justify left bottom)
				(hide yes)
			)
		)
		(property "Value" "+3V3"
			(at 27.94 172.974 0)
			(effects
				(font
					(size 1.27 1.27)
					(thickness 0.15)
				)
			)
		)
		(property "Footprint" ""
			(at 43.18 184.15 0)
			(effects
				(font
					(size 1.27 1.27)
					(thickness 0.15)
				)
				(justify left bottom)
				(hide yes)
			)
		)
		(property "Datasheet" ""
			(at 43.18 186.69 0)
			(effects
				(font
					(size 1.27 1.27)
					(thickness 0.15)
				)
				(justify left bottom)
				(hide yes)
			)
		)
		(property "Description" ""
			(at 27.94 176.53 0)
			(effects
				(font
					(size 1.27 1.27)
				)
				(hide yes)
			)
		)
		(property "Author" "Antmicro"
			(at 43.18 179.07 0)
			(effects
				(font
					(size 1.27 1.27)
					(thickness 0.15)
				)
				(justify left bottom)
				(hide yes)
			)
		)
		(property "License" "Apache-2.0"
			(at 43.18 181.61 0)
			(effects
				(font
					(size 1.27 1.27)
					(thickness 0.15)
				)
				(justify left bottom)
				(hide yes)
			)
		)
		(pin "1"
		)
		(instances
			(project "jetson-agx-thor-baseboard"
				(path ""
					(reference "#PWR0470")
					(unit 1)
				)
			)
		)
	)
	(symbol
		(lib_id "antmicroResistors0402:R_2R2_0402")
		(at 176.53 255.27 0)
		(unit 1)
		(exclude_from_sim no)
		(in_bom yes)
		(on_board yes)
		(dnp no)
		(property "Reference" "R331"
			(at 178.816 252.984 0)
			(effects
				(font
					(size 1.27 1.27)
					(thickness 0.15)
				)
			)
		)
		(property "Value" "R_2R2_0402"
			(at 196.85 267.97 0)
			(effects
				(font
					(size 1.27 1.27)
					(thickness 0.15)
				)
				(justify left bottom)
				(hide yes)
			)
		)
		(property "Footprint" "antmicro-footprints:R_0402_1005Metric"
			(at 196.85 270.51 0)
			(effects
				(font
					(size 1.27 1.27)
					(thickness 0.15)
				)
				(justify left bottom)
				(hide yes)
			)
		)
		(property "Datasheet" "https://www.bourns.com/docs/product-datasheets/cr.pdf"
			(at 196.85 273.05 0)
			(effects
				(font
					(size 1.27 1.27)
					(thickness 0.15)
				)
				(justify left bottom)
				(hide yes)
			)
		)
		(property "Description" "SMD Chip Resistor, 2.2 ohm, ± 1%, 62.5 mW, 0402 [1005 Metric], Thick Film, General Purpose"
			(at 196.85 285.75 0)
			(effects
				(font
					(size 1.27 1.27)
				)
				(justify left bottom)
				(hide yes)
			)
		)
		(property "MPN" "CR0402-FX-2R20GLF"
			(at 196.85 275.59 0)
			(effects
				(font
					(size 1.27 1.27)
					(thickness 0.15)
				)
				(justify left bottom)
				(hide yes)
			)
		)
		(property "Manufacturer" "Bourns"
			(at 196.85 278.13 0)
			(effects
				(font
					(size 1.27 1.27)
					(thickness 0.15)
				)
				(justify left bottom)
				(hide yes)
			)
		)
		(property "License" "Apache-2.0"
			(at 196.85 280.67 0)
			(effects
				(font
					(size 1.27 1.27)
					(thickness 0.15)
				)
				(justify left bottom)
				(hide yes)
			)
		)
		(property "Author" "Antmicro"
			(at 196.85 283.21 0)
			(effects
				(font
					(size 1.27 1.27)
					(thickness 0.15)
				)
				(justify left bottom)
				(hide yes)
			)
		)
		(property "Val" "2R2"
			(at 178.816 257.556 0)
			(effects
				(font
					(size 1.27 1.27)
					(thickness 0.15)
				)
			)
		)
		(property "Tolerance" "1%"
			(at 196.85 265.43 0)
			(effects
				(font
					(size 1.27 1.27)
				)
				(justify left bottom)
				(hide yes)
			)
		)
		(pin "2"
		)
		(pin "1"
		)
		(instances
			(project "jetson-agx-thor-baseboard"
				(path ""
					(reference "R331")
					(unit 1)
				)
			)
		)
	)
	(symbol
		(lib_id "antmicropower:+3V3")
		(at 92.71 163.83 0)
		(unit 1)
		(exclude_from_sim no)
		(in_bom yes)
		(on_board yes)
		(dnp no)
		(property "Reference" "#PWR0197"
			(at 107.95 163.83 0)
			(effects
				(font
					(size 1.27 1.27)
					(thickness 0.15)
				)
				(justify left bottom)
				(hide yes)
			)
		)
		(property "Value" "+3V3"
			(at 92.71 160.274 0)
			(effects
				(font
					(size 1.27 1.27)
					(thickness 0.15)
				)
			)
		)
		(property "Footprint" ""
			(at 107.95 171.45 0)
			(effects
				(font
					(size 1.27 1.27)
					(thickness 0.15)
				)
				(justify left bottom)
				(hide yes)
			)
		)
		(property "Datasheet" ""
			(at 107.95 173.99 0)
			(effects
				(font
					(size 1.27 1.27)
					(thickness 0.15)
				)
				(justify left bottom)
				(hide yes)
			)
		)
		(property "Description" ""
			(at 92.71 163.83 0)
			(effects
				(font
					(size 1.27 1.27)
				)
				(hide yes)
			)
		)
		(property "Author" "Antmicro"
			(at 107.95 166.37 0)
			(effects
				(font
					(size 1.27 1.27)
					(thickness 0.15)
				)
				(justify left bottom)
				(hide yes)
			)
		)
		(property "License" "Apache-2.0"
			(at 107.95 168.91 0)
			(effects
				(font
					(size 1.27 1.27)
					(thickness 0.15)
				)
				(justify left bottom)
				(hide yes)
			)
		)
		(pin "1"
		)
		(instances
			(project "jetson-agx-thor-baseboard"
				(path ""
					(reference "#PWR0197")
					(unit 1)
				)
			)
		)
	)
	(symbol
		(lib_id "antmicroCapacitors0402:C_100n_0402")
		(at 289.56 228.6 180)
		(unit 1)
		(exclude_from_sim no)
		(in_bom yes)
		(on_board yes)
		(dnp no)
		(property "Reference" "C103"
			(at 293.37 226.568 0)
			(effects
				(font
					(size 1.27 1.27)
				)
				(justify left bottom)
			)
		)
		(property "Value" "C_100n_0402"
			(at 269.24 218.44 0)
			(effects
				(font
					(size 1.27 1.27)
					(thickness 0.15)
				)
				(justify left bottom)
				(hide yes)
			)
		)
		(property "Footprint" "antmicro-footprints:C_0402_1005Metric"
			(at 269.24 215.9 0)
			(effects
				(font
					(size 1.27 1.27)
					(thickness 0.15)
				)
				(justify left bottom)
				(hide yes)
			)
		)
		(property "Datasheet" "https://www.murata.com/products/productdetail?partno=GRM155R61H104KE14%23"
			(at 269.24 213.36 0)
			(effects
				(font
					(size 1.27 1.27)
					(thickness 0.15)
				)
				(justify left bottom)
				(hide yes)
			)
		)
		(property "Description" "SMD Multilayer Ceramic Capacitor, 0.1 µF, 50 V, 0402 [1005 Metric], ± 10%, X5R, GRM Series"
			(at 289.56 228.6 0)
			(effects
				(font
					(size 1.27 1.27)
				)
				(hide yes)
			)
		)
		(property "Manufacturer" "Murata"
			(at 269.24 208.28 0)
			(effects
				(font
					(size 1.27 1.27)
					(thickness 0.15)
				)
				(justify left bottom)
				(hide yes)
			)
		)
		(property "MPN" "GRM155R61H104KE14D"
			(at 269.24 210.82 0)
			(effects
				(font
					(size 1.27 1.27)
					(thickness 0.15)
				)
				(justify left bottom)
				(hide yes)
			)
		)
		(property "Val" "100n"
			(at 285.75 229.235 0)
			(effects
				(font
					(size 1.27 1.27)
					(thickness 0.15)
				)
				(justify left bottom)
			)
		)
		(property "License" "Apache-2.0"
			(at 269.24 205.74 0)
			(effects
				(font
					(size 1.27 1.27)
					(thickness 0.15)
				)
				(justify left bottom)
				(hide yes)
			)
		)
		(property "Author" "Antmicro"
			(at 269.24 203.2 0)
			(effects
				(font
					(size 1.27 1.27)
					(thickness 0.15)
				)
				(justify left bottom)
				(hide yes)
			)
		)
		(property "Voltage" "50V"
			(at 269.24 200.66 0)
			(effects
				(font
					(size 1.27 1.27)
				)
				(justify left bottom)
				(hide yes)
			)
		)
		(property "Dielectric" "X5R"
			(at 269.24 198.12 0)
			(effects
				(font
					(size 1.27 1.27)
				)
				(justify left bottom)
				(hide yes)
			)
		)
		(pin "1"
		)
		(pin "2"
		)
		(instances
			(project "jetson-agx-thor-baseboard"
				(path ""
					(reference "C103")
					(unit 1)
				)
			)
		)
	)
	(symbol
		(lib_id "antmicroResistors0402:R_10k_0402")
		(at 100.33 165.1 270)
		(unit 1)
		(exclude_from_sim no)
		(in_bom yes)
		(on_board yes)
		(dnp no)
		(property "Reference" "R83"
			(at 101.6 166.116 90)
			(effects
				(font
					(size 1.27 1.27)
					(thickness 0.15)
				)
				(justify left)
			)
		)
		(property "Value" "R_10k_0402"
			(at 87.63 185.42 0)
			(effects
				(font
					(size 1.27 1.27)
					(thickness 0.15)
				)
				(justify left bottom)
				(hide yes)
			)
		)
		(property "Footprint" "antmicro-footprints:R_0402_1005Metric"
			(at 85.09 185.42 0)
			(effects
				(font
					(size 1.27 1.27)
					(thickness 0.15)
				)
				(justify left bottom)
				(hide yes)
			)
		)
		(property "Datasheet" "https://www.bourns.com/docs/product-datasheets/cr.pdf"
			(at 82.55 185.42 0)
			(effects
				(font
					(size 1.27 1.27)
					(thickness 0.15)
				)
				(justify left bottom)
				(hide yes)
			)
		)
		(property "Description" "SMD Chip Resistor, 10 kohm, ± 1%, 62.5 mW, 0402 [1005 Metric], Thick Film, General Purpose"
			(at 100.33 165.1 0)
			(effects
				(font
					(size 1.27 1.27)
				)
				(hide yes)
			)
		)
		(property "MPN" "CR0402-FX-1002GLF"
			(at 80.01 185.42 0)
			(effects
				(font
					(size 1.27 1.27)
					(thickness 0.15)
				)
				(justify left bottom)
				(hide yes)
			)
		)
		(property "Manufacturer" "Bourns"
			(at 77.47 185.42 0)
			(effects
				(font
					(size 1.27 1.27)
					(thickness 0.15)
				)
				(justify left bottom)
				(hide yes)
			)
		)
		(property "License" "Apache-2.0"
			(at 74.93 185.42 0)
			(effects
				(font
					(size 1.27 1.27)
					(thickness 0.15)
				)
				(justify left bottom)
				(hide yes)
			)
		)
		(property "Author" "Antmicro"
			(at 72.39 185.42 0)
			(effects
				(font
					(size 1.27 1.27)
					(thickness 0.15)
				)
				(justify left bottom)
				(hide yes)
			)
		)
		(property "Val" "10k"
			(at 101.6 168.656 90)
			(effects
				(font
					(size 1.27 1.27)
					(thickness 0.15)
				)
				(justify left)
			)
		)
		(property "Tolerance" "1%"
			(at 90.17 185.42 0)
			(effects
				(font
					(size 1.27 1.27)
				)
				(justify left bottom)
				(hide yes)
			)
		)
		(pin "2"
		)
		(pin "1"
		)
		(instances
			(project "jetson-agx-thor-baseboard"
				(path ""
					(reference "R83")
					(unit 1)
				)
			)
		)
	)
	(symbol
		(lib_id "antmicropower:GND")
		(at 220.98 196.85 0)
		(unit 1)
		(exclude_from_sim no)
		(in_bom yes)
		(on_board yes)
		(dnp no)
		(property "Reference" "#PWR0518"
			(at 220.98 203.2 0)
			(effects
				(font
					(size 1.27 1.27)
				)
				(justify left bottom)
				(hide yes)
			)
		)
		(property "Value" "GND"
			(at 220.98 200.66 0)
			(effects
				(font
					(size 1.27 1.27)
					(thickness 0.15)
				)
			)
		)
		(property "Footprint" ""
			(at 229.87 204.47 0)
			(effects
				(font
					(size 1.27 1.27)
					(thickness 0.15)
				)
				(justify left bottom)
				(hide yes)
			)
		)
		(property "Datasheet" ""
			(at 229.87 209.55 0)
			(effects
				(font
					(size 1.27 1.27)
					(thickness 0.15)
				)
				(justify left bottom)
				(hide yes)
			)
		)
		(property "Description" ""
			(at 220.98 196.85 0)
			(effects
				(font
					(size 1.27 1.27)
				)
				(hide yes)
			)
		)
		(property "Author" "Antmicro"
			(at 229.87 204.47 0)
			(effects
				(font
					(size 1.27 1.27)
					(thickness 0.15)
				)
				(justify left bottom)
				(hide yes)
			)
		)
		(property "License" "Apache-2.0"
			(at 229.87 207.01 0)
			(effects
				(font
					(size 1.27 1.27)
					(thickness 0.15)
				)
				(justify left bottom)
				(hide yes)
			)
		)
		(pin "1"
		)
		(instances
			(project "jetson-agx-thor-baseboard"
				(path ""
					(reference "#PWR0518")
					(unit 1)
				)
			)
		)
	)
	(symbol
		(lib_id "antmicroTransistorsFETsMOSFETsArrays:DMC2400UV-7")
		(at 223.52 265.43 180)
		(unit 1)
		(exclude_from_sim no)
		(in_bom yes)
		(on_board yes)
		(dnp no)
		(property "Reference" "Q29"
			(at 217.17 268.478 0)
			(effects
				(font
					(size 1.27 1.27)
					(thickness 0.15)
				)
			)
		)
		(property "Value" "DMC2400UV-7"
			(at 195.58 260.35 0)
			(effects
				(font
					(size 1.27 1.27)
					(thickness 0.15)
				)
				(justify left bottom)
				(hide yes)
			)
		)
		(property "Footprint" "antmicro-footprints:SOT-563"
			(at 195.58 257.81 0)
			(effects
				(font
					(size 1.27 1.27)
					(thickness 0.15)
				)
				(justify left bottom)
				(hide yes)
			)
		)
		(property "Datasheet" "https://www.mouser.com/datasheet/2/115/DIOD_S_A0010038249_1-2543538.pdf"
			(at 195.58 255.27 0)
			(effects
				(font
					(size 1.27 1.27)
					(thickness 0.15)
				)
				(justify left bottom)
				(hide yes)
			)
		)
		(property "Description" "Dual MOSFET, Complementary N and P Channel, 20 V, 20 V, 1.03 A, 1.03 A, 0.3 ohm"
			(at 195.58 242.57 0)
			(effects
				(font
					(size 1.27 1.27)
				)
				(justify left bottom)
				(hide yes)
			)
		)
		(property "MPN" "DMC2400UV-7"
			(at 217.17 271.018 0)
			(effects
				(font
					(size 1.27 1.27)
					(thickness 0.15)
				)
			)
		)
		(property "Manufacturer" "Diodes Incorporated"
			(at 195.58 250.19 0)
			(effects
				(font
					(size 1.27 1.27)
					(thickness 0.15)
				)
				(justify left bottom)
				(hide yes)
			)
		)
		(property "Author" "Antmicro"
			(at 195.58 247.65 0)
			(effects
				(font
					(size 1.27 1.27)
					(thickness 0.15)
				)
				(justify left bottom)
				(hide yes)
			)
		)
		(property "License" "Apache-2.0"
			(at 195.58 245.11 0)
			(effects
				(font
					(size 1.27 1.27)
					(thickness 0.15)
				)
				(justify left bottom)
				(hide yes)
			)
		)
		(pin "5"
		)
		(pin "3"
		)
		(pin "6"
		)
		(pin "2"
		)
		(pin "1"
		)
		(pin "4"
		)
		(instances
			(project "jetson-agx-thor-baseboard"
				(path ""
					(reference "Q29")
					(unit 1)
				)
			)
		)
	)
	(symbol
		(lib_id "antmicropower:GND")
		(at 199.39 163.83 0)
		(unit 1)
		(exclude_from_sim no)
		(in_bom yes)
		(on_board yes)
		(dnp no)
		(property "Reference" "#PWR0507"
			(at 199.39 170.18 0)
			(effects
				(font
					(size 1.27 1.27)
				)
				(justify left bottom)
				(hide yes)
			)
		)
		(property "Value" "GND"
			(at 199.39 167.64 0)
			(effects
				(font
					(size 1.27 1.27)
					(thickness 0.15)
				)
			)
		)
		(property "Footprint" ""
			(at 208.28 171.45 0)
			(effects
				(font
					(size 1.27 1.27)
					(thickness 0.15)
				)
				(justify left bottom)
				(hide yes)
			)
		)
		(property "Datasheet" ""
			(at 208.28 176.53 0)
			(effects
				(font
					(size 1.27 1.27)
					(thickness 0.15)
				)
				(justify left bottom)
				(hide yes)
			)
		)
		(property "Description" ""
			(at 199.39 163.83 0)
			(effects
				(font
					(size 1.27 1.27)
				)
				(hide yes)
			)
		)
		(property "Author" "Antmicro"
			(at 208.28 171.45 0)
			(effects
				(font
					(size 1.27 1.27)
					(thickness 0.15)
				)
				(justify left bottom)
				(hide yes)
			)
		)
		(property "License" "Apache-2.0"
			(at 208.28 173.99 0)
			(effects
				(font
					(size 1.27 1.27)
					(thickness 0.15)
				)
				(justify left bottom)
				(hide yes)
			)
		)
		(pin "1"
		)
		(instances
			(project "jetson-agx-thor-baseboard"
				(path ""
					(reference "#PWR0507")
					(unit 1)
				)
			)
		)
	)
	(symbol
		(lib_id "antmicroDiodesRectifiersSingle:RB521S30T1G")
		(at 172.72 231.14 180)
		(unit 1)
		(exclude_from_sim no)
		(in_bom yes)
		(on_board yes)
		(dnp no)
		(property "Reference" "D57"
			(at 170.688 224.79 0)
			(effects
				(font
					(size 1.27 1.27)
				)
			)
		)
		(property "Value" "RB521S30T1G"
			(at 149.86 215.9 0)
			(effects
				(font
					(size 1.27 1.27)
					(thickness 0.15)
				)
				(justify left bottom)
				(hide yes)
			)
		)
		(property "Footprint" "antmicro-footprints:SOD-523"
			(at 149.86 220.98 0)
			(effects
				(font
					(size 1.27 1.27)
					(thickness 0.15)
				)
				(justify left bottom)
				(hide yes)
			)
		)
		(property "Datasheet" "https://www.onsemi.com/pdf/datasheet/rb521s30t1-d.pdf"
			(at 149.86 218.44 0)
			(effects
				(font
					(size 1.27 1.27)
					(thickness 0.15)
				)
				(justify left bottom)
				(hide yes)
			)
		)
		(property "Description" "Small Signal Schottky Diode, Single, 30 V, 200 mA, 500 mV, 1 A, 125 °C"
			(at 172.72 231.14 0)
			(effects
				(font
					(size 1.27 1.27)
				)
				(hide yes)
			)
		)
		(property "MPN" "RB521S30T1G"
			(at 170.688 227.33 0)
			(effects
				(font
					(size 1.27 1.27)
					(thickness 0.15)
				)
			)
		)
		(property "Manufacturer" "ON Semiconductor"
			(at 149.86 213.36 0)
			(effects
				(font
					(size 1.27 1.27)
					(thickness 0.15)
				)
				(justify left bottom)
				(hide yes)
			)
		)
		(property "Author" "Antmicro"
			(at 149.86 210.82 0)
			(effects
				(font
					(size 1.27 1.27)
					(thickness 0.15)
				)
				(justify left bottom)
				(hide yes)
			)
		)
		(property "License" "Apache-2.0"
			(at 149.86 208.28 0)
			(effects
				(font
					(size 1.27 1.27)
					(thickness 0.15)
				)
				(justify left bottom)
				(hide yes)
			)
		)
		(pin "1"
		)
		(pin "2"
		)
		(instances
			(project "jetson-agx-thor-baseboard"
				(path ""
					(reference "D57")
					(unit 1)
				)
			)
		)
	)
	(symbol
		(lib_id "antmicropower:+3V3")
		(at 236.22 163.83 0)
		(mirror y)
		(unit 1)
		(exclude_from_sim no)
		(in_bom yes)
		(on_board yes)
		(dnp no)
		(property "Reference" "#PWR074"
			(at 220.98 163.83 0)
			(effects
				(font
					(size 1.27 1.27)
					(thickness 0.15)
				)
				(justify left bottom)
				(hide yes)
			)
		)
		(property "Value" "+3V3"
			(at 236.22 160.274 0)
			(effects
				(font
					(size 1.27 1.27)
					(thickness 0.15)
				)
			)
		)
		(property "Footprint" ""
			(at 220.98 171.45 0)
			(effects
				(font
					(size 1.27 1.27)
					(thickness 0.15)
				)
				(justify left bottom)
				(hide yes)
			)
		)
		(property "Datasheet" ""
			(at 220.98 173.99 0)
			(effects
				(font
					(size 1.27 1.27)
					(thickness 0.15)
				)
				(justify left bottom)
				(hide yes)
			)
		)
		(property "Description" ""
			(at 236.22 163.83 0)
			(effects
				(font
					(size 1.27 1.27)
				)
				(hide yes)
			)
		)
		(property "Author" "Antmicro"
			(at 220.98 166.37 0)
			(effects
				(font
					(size 1.27 1.27)
					(thickness 0.15)
				)
				(justify left bottom)
				(hide yes)
			)
		)
		(property "License" "Apache-2.0"
			(at 220.98 168.91 0)
			(effects
				(font
					(size 1.27 1.27)
					(thickness 0.15)
				)
				(justify left bottom)
				(hide yes)
			)
		)
		(pin "1"
		)
		(instances
			(project "jetson-agx-thor-baseboard"
				(path ""
					(reference "#PWR074")
					(unit 1)
				)
			)
		)
	)
	(symbol
		(lib_id "antmicroResistors0402:R_10k_0402")
		(at 236.22 171.45 270)
		(mirror x)
		(unit 1)
		(exclude_from_sim no)
		(in_bom no)
		(on_board yes)
		(dnp yes)
		(property "Reference" "R321"
			(at 234.95 167.64 90)
			(effects
				(font
					(size 1.27 1.27)
				)
				(justify right)
			)
		)
		(property "Value" "R_10k_0402"
			(at 223.52 151.13 0)
			(effects
				(font
					(size 1.27 1.27)
					(thickness 0.15)
				)
				(justify left bottom)
				(hide yes)
			)
		)
		(property "Footprint" "antmicro-footprints:R_0402_1005Metric"
			(at 220.98 151.13 0)
			(effects
				(font
					(size 1.27 1.27)
					(thickness 0.15)
				)
				(justify left bottom)
				(hide yes)
			)
		)
		(property "Datasheet" "https://www.bourns.com/docs/product-datasheets/cr.pdf"
			(at 218.44 151.13 0)
			(effects
				(font
					(size 1.27 1.27)
					(thickness 0.15)
				)
				(justify left bottom)
				(hide yes)
			)
		)
		(property "Description" "SMD Chip Resistor, 10 kohm, ± 1%, 62.5 mW, 0402 [1005 Metric], Thick Film, General Purpose"
			(at 236.22 171.45 0)
			(effects
				(font
					(size 1.27 1.27)
				)
				(hide yes)
			)
		)
		(property "Manufacturer" "Bourns"
			(at 213.36 151.13 0)
			(effects
				(font
					(size 1.27 1.27)
					(thickness 0.15)
				)
				(justify left bottom)
				(hide yes)
			)
		)
		(property "MPN" "CR0402-FX-1002GLF"
			(at 215.9 151.13 0)
			(effects
				(font
					(size 1.27 1.27)
					(thickness 0.15)
				)
				(justify left bottom)
				(hide yes)
			)
		)
		(property "Val" "10k"
			(at 234.95 170.18 90)
			(effects
				(font
					(size 1.27 1.27)
					(thickness 0.15)
				)
				(justify right)
			)
		)
		(property "License" "Apache-2.0"
			(at 210.82 151.13 0)
			(effects
				(font
					(size 1.27 1.27)
					(thickness 0.15)
				)
				(justify left bottom)
				(hide yes)
			)
		)
		(property "Author" "Antmicro"
			(at 208.28 151.13 0)
			(effects
				(font
					(size 1.27 1.27)
					(thickness 0.15)
				)
				(justify left bottom)
				(hide yes)
			)
		)
		(property "Tolerance" "1%"
			(at 226.06 151.13 0)
			(effects
				(font
					(size 1.27 1.27)
				)
				(justify left bottom)
				(hide yes)
			)
		)
		(pin "1"
		)
		(pin "2"
		)
		(instances
			(project "jetson-agx-thor-baseboard"
				(path ""
					(reference "R321")
					(unit 1)
				)
			)
		)
	)
	(symbol
		(lib_id "antmicropower:GND")
		(at 167.64 242.57 0)
		(mirror y)
		(unit 1)
		(exclude_from_sim no)
		(in_bom yes)
		(on_board yes)
		(dnp no)
		(property "Reference" "#PWR0769"
			(at 167.64 248.92 0)
			(effects
				(font
					(size 1.27 1.27)
				)
				(justify left bottom)
				(hide yes)
			)
		)
		(property "Value" "GND"
			(at 167.64 246.38 0)
			(effects
				(font
					(size 1.27 1.27)
					(thickness 0.15)
				)
			)
		)
		(property "Footprint" ""
			(at 158.75 250.19 0)
			(effects
				(font
					(size 1.27 1.27)
					(thickness 0.15)
				)
				(justify left bottom)
				(hide yes)
			)
		)
		(property "Datasheet" ""
			(at 158.75 255.27 0)
			(effects
				(font
					(size 1.27 1.27)
					(thickness 0.15)
				)
				(justify left bottom)
				(hide yes)
			)
		)
		(property "Description" ""
			(at 167.64 242.57 0)
			(effects
				(font
					(size 1.27 1.27)
				)
				(hide yes)
			)
		)
		(property "Author" "Antmicro"
			(at 158.75 250.19 0)
			(effects
				(font
					(size 1.27 1.27)
					(thickness 0.15)
				)
				(justify left bottom)
				(hide yes)
			)
		)
		(property "License" "Apache-2.0"
			(at 158.75 252.73 0)
			(effects
				(font
					(size 1.27 1.27)
					(thickness 0.15)
				)
				(justify left bottom)
				(hide yes)
			)
		)
		(pin "1"
		)
		(instances
			(project "jetson-agx-thor-baseboard"
				(path ""
					(reference "#PWR0769")
					(unit 1)
				)
			)
		)
	)
	(symbol
		(lib_id "antmicroResistors0402:R_12k_0402")
		(at 115.57 184.15 0)
		(unit 1)
		(exclude_from_sim no)
		(in_bom yes)
		(on_board yes)
		(dnp no)
		(property "Reference" "R85"
			(at 118.11 182.372 0)
			(effects
				(font
					(size 1.27 1.27)
					(thickness 0.15)
				)
			)
		)
		(property "Value" "R_12k_0402"
			(at 135.89 196.85 0)
			(effects
				(font
					(size 1.27 1.27)
					(thickness 0.15)
				)
				(justify left bottom)
				(hide yes)
			)
		)
		(property "Footprint" "antmicro-footprints:R_0402_1005Metric"
			(at 135.89 199.39 0)
			(effects
				(font
					(size 1.27 1.27)
					(thickness 0.15)
				)
				(justify left bottom)
				(hide yes)
			)
		)
		(property "Datasheet" "https://www.bourns.com/docs/product-datasheets/cr.pdf"
			(at 135.89 201.93 0)
			(effects
				(font
					(size 1.27 1.27)
					(thickness 0.15)
				)
				(justify left bottom)
				(hide yes)
			)
		)
		(property "Description" "SMD Chip Resistor, 12 kohm, ± 1%, 62.5 mW, 0402 [1005 Metric], Thick Film, General Purpose"
			(at 115.57 184.15 0)
			(effects
				(font
					(size 1.27 1.27)
				)
				(hide yes)
			)
		)
		(property "MPN" "CR0402-FX-1202GLF"
			(at 135.89 204.47 0)
			(effects
				(font
					(size 1.27 1.27)
					(thickness 0.15)
				)
				(justify left bottom)
				(hide yes)
			)
		)
		(property "Manufacturer" "Bourns"
			(at 135.89 207.01 0)
			(effects
				(font
					(size 1.27 1.27)
					(thickness 0.15)
				)
				(justify left bottom)
				(hide yes)
			)
		)
		(property "License" "Apache-2.0"
			(at 135.89 209.55 0)
			(effects
				(font
					(size 1.27 1.27)
					(thickness 0.15)
				)
				(justify left bottom)
				(hide yes)
			)
		)
		(property "Author" "Antmicro"
			(at 135.89 212.09 0)
			(effects
				(font
					(size 1.27 1.27)
					(thickness 0.15)
				)
				(justify left bottom)
				(hide yes)
			)
		)
		(property "Val" "12k"
			(at 118.11 186.182 0)
			(effects
				(font
					(size 1.27 1.27)
					(thickness 0.15)
				)
			)
		)
		(property "Tolerance" "1%"
			(at 135.89 194.31 0)
			(effects
				(font
					(size 1.27 1.27)
				)
				(justify left bottom)
				(hide yes)
			)
		)
		(pin "2"
		)
		(pin "1"
		)
		(instances
			(project "jetson-agx-thor-baseboard"
				(path ""
					(reference "R85")
					(unit 1)
				)
			)
		)
	)
	(symbol
		(lib_id "antmicroResistors0402:R_100k_0402")
		(at 213.36 195.58 270)
		(mirror x)
		(unit 1)
		(exclude_from_sim no)
		(in_bom yes)
		(on_board yes)
		(dnp no)
		(property "Reference" "R327"
			(at 212.09 191.77 90)
			(effects
				(font
					(size 1.27 1.27)
					(thickness 0.15)
				)
				(justify right)
			)
		)
		(property "Value" "R_100k_0402"
			(at 200.66 175.26 0)
			(effects
				(font
					(size 1.27 1.27)
					(thickness 0.15)
				)
				(justify left bottom)
				(hide yes)
			)
		)
		(property "Footprint" "antmicro-footprints:R_0402_1005Metric"
			(at 198.12 175.26 0)
			(effects
				(font
					(size 1.27 1.27)
					(thickness 0.15)
				)
				(justify left bottom)
				(hide yes)
			)
		)
		(property "Datasheet" "https://www.bourns.com/docs/product-datasheets/cr.pdf"
			(at 195.58 175.26 0)
			(effects
				(font
					(size 1.27 1.27)
					(thickness 0.15)
				)
				(justify left bottom)
				(hide yes)
			)
		)
		(property "Description" "SMD Chip Resistor, 100 kohm, ± 1%, 62.5 mW, 0402 [1005 Metric], Thick Film, General Purpose"
			(at 182.88 175.26 0)
			(effects
				(font
					(size 1.27 1.27)
				)
				(justify left bottom)
				(hide yes)
			)
		)
		(property "MPN" "CR0402-FX-1003GLF"
			(at 193.04 175.26 0)
			(effects
				(font
					(size 1.27 1.27)
					(thickness 0.15)
				)
				(justify left bottom)
				(hide yes)
			)
		)
		(property "Manufacturer" "Bourns"
			(at 190.5 175.26 0)
			(effects
				(font
					(size 1.27 1.27)
					(thickness 0.15)
				)
				(justify left bottom)
				(hide yes)
			)
		)
		(property "License" "Apache-2.0"
			(at 187.96 175.26 0)
			(effects
				(font
					(size 1.27 1.27)
					(thickness 0.15)
				)
				(justify left bottom)
				(hide yes)
			)
		)
		(property "Author" "Antmicro"
			(at 185.42 175.26 0)
			(effects
				(font
					(size 1.27 1.27)
					(thickness 0.15)
				)
				(justify left bottom)
				(hide yes)
			)
		)
		(property "Val" "100k"
			(at 212.09 194.31 90)
			(effects
				(font
					(size 1.27 1.27)
					(thickness 0.15)
				)
				(justify right)
			)
		)
		(property "Tolerance" "1%"
			(at 203.2 175.26 0)
			(effects
				(font
					(size 1.27 1.27)
				)
				(justify left bottom)
				(hide yes)
			)
		)
		(pin "2"
		)
		(pin "1"
		)
		(instances
			(project ""
				(path ""
					(reference "R327")
					(unit 1)
				)
			)
		)
	)
	(symbol
		(lib_id "antmicroUSBConnectors:USB-C_Kycon_KUSBX-SL2-CS1N24-B-TR")
		(at 351.79 55.88 0)
		(mirror y)
		(unit 1)
		(exclude_from_sim no)
		(in_bom yes)
		(on_board yes)
		(dnp no)
		(property "Reference" "J6"
			(at 365.125 48.26 0)
			(effects
				(font
					(size 1.27 1.27)
					(thickness 0.15)
				)
			)
		)
		(property "Value" "USB-C_Kycon_KUSBX-SL2-CS1N24-B-TR"
			(at 308.61 60.96 0)
			(effects
				(font
					(size 1.27 1.27)
					(thickness 0.15)
				)
				(justify left bottom)
				(hide yes)
			)
		)
		(property "Footprint" "antmicro-footprints:USB-C_Receptacle_Kycon_KUSBX-SL2-CS1N24-B-TR"
			(at 308.61 63.5 0)
			(effects
				(font
					(size 1.27 1.27)
					(thickness 0.15)
				)
				(justify left bottom)
				(hide yes)
			)
		)
		(property "Datasheet" "https://www.kycon.com/Pub_Eng_Draw/KUSBX-SL2-CS1N24-B-TR.pdf"
			(at 308.61 66.04 0)
			(effects
				(font
					(size 1.27 1.27)
					(thickness 0.15)
				)
				(justify left bottom)
				(hide yes)
			)
		)
		(property "Description" "USB-C (USB TYPE-C) USB 3.2 Gen 2 (USB 3.1 Gen 2, Superspeed + (USB 3.1)) USB PD Receptacle Connector 24 Position Surface Mount"
			(at 308.61 78.74 0)
			(effects
				(font
					(size 1.27 1.27)
				)
				(justify left bottom)
				(hide yes)
			)
		)
		(property "MPN" "KUSBX-SL2-CS1N24-B-TR"
			(at 365.125 50.8 0)
			(effects
				(font
					(size 1.27 1.27)
					(thickness 0.15)
				)
			)
		)
		(property "Manufacturer" "Kycon"
			(at 308.61 71.12 0)
			(effects
				(font
					(size 1.27 1.27)
					(thickness 0.15)
				)
				(justify left bottom)
				(hide yes)
			)
		)
		(property "License" "Apache-2.0"
			(at 308.61 73.66 0)
			(effects
				(font
					(size 1.27 1.27)
					(thickness 0.15)
				)
				(justify left bottom)
				(hide yes)
			)
		)
		(property "Author" "Antmicro"
			(at 308.61 76.2 0)
			(effects
				(font
					(size 1.27 1.27)
					(thickness 0.15)
				)
				(justify left bottom)
				(hide yes)
			)
		)
		(pin "A6"
		)
		(pin "A2"
		)
		(pin "SH"
		)
		(pin "A1"
		)
		(pin "B12"
		)
		(pin "B7"
		)
		(pin "A12"
		)
		(pin "A8"
		)
		(pin "B1"
		)
		(pin "B8"
		)
		(pin "A3"
		)
		(pin "B10"
		)
		(pin "B3"
		)
		(pin "A7"
		)
		(pin "A11"
		)
		(pin "B5"
		)
		(pin "B9"
		)
		(pin "A5"
		)
		(pin "A9"
		)
		(pin "B4"
		)
		(pin "A4"
		)
		(pin "B6"
		)
		(pin "B2"
		)
		(pin "B11"
		)
		(pin "A10"
		)
		(instances
			(project "jetson-agx-thor-baseboard"
				(path ""
					(reference "J6")
					(unit 1)
				)
			)
		)
	)
	(symbol
		(lib_id "antmicroResistors0402:R_0R_0402")
		(at 52.07 251.46 0)
		(unit 1)
		(exclude_from_sim no)
		(in_bom no)
		(on_board yes)
		(dnp yes)
		(property "Reference" "R378"
			(at 50.038 250.698 0)
			(effects
				(font
					(size 1.27 1.27)
					(thickness 0.15)
				)
			)
		)
		(property "Value" "R_0R_0402"
			(at 72.39 264.16 0)
			(effects
				(font
					(size 1.27 1.27)
					(thickness 0.15)
				)
				(justify left bottom)
				(hide yes)
			)
		)
		(property "Footprint" "antmicro-footprints:R_0402_1005Metric"
			(at 72.39 266.7 0)
			(effects
				(font
					(size 1.27 1.27)
					(thickness 0.15)
				)
				(justify left bottom)
				(hide yes)
			)
		)
		(property "Datasheet" "https://industrial.panasonic.com/cdbs/www-data/pdf/RDA0000/AOA0000C301.pdf"
			(at 72.39 269.24 0)
			(effects
				(font
					(size 1.27 1.27)
					(thickness 0.15)
				)
				(justify left bottom)
				(hide yes)
			)
		)
		(property "Description" "SMD Chip Resistor, Jumper, 0 ohm, 100 mW, 0402 [1005 Metric], Thick Film, General Purpose"
			(at 72.39 284.48 0)
			(effects
				(font
					(size 1.27 1.27)
				)
				(justify left bottom)
				(hide yes)
			)
		)
		(property "MPN" "ERJ2GE0R00X"
			(at 72.39 271.78 0)
			(effects
				(font
					(size 1.27 1.27)
					(thickness 0.15)
				)
				(justify left bottom)
				(hide yes)
			)
		)
		(property "Manufacturer" "Panasonic"
			(at 72.39 274.32 0)
			(effects
				(font
					(size 1.27 1.27)
					(thickness 0.15)
				)
				(justify left bottom)
				(hide yes)
			)
		)
		(property "License" "Apache-2.0"
			(at 72.39 276.86 0)
			(effects
				(font
					(size 1.27 1.27)
					(thickness 0.15)
				)
				(justify left bottom)
				(hide yes)
			)
		)
		(property "Author" "Antmicro"
			(at 72.39 279.4 0)
			(effects
				(font
					(size 1.27 1.27)
					(thickness 0.15)
				)
				(justify left bottom)
				(hide yes)
			)
		)
		(property "Val" "0R"
			(at 58.42 250.698 0)
			(effects
				(font
					(size 1.27 1.27)
					(thickness 0.15)
				)
			)
		)
		(property "Tolerance" "~"
			(at 72.39 261.62 0)
			(effects
				(font
					(size 1.27 1.27)
				)
				(justify left bottom)
				(hide yes)
			)
		)
		(property "Current" "1A"
			(at 72.39 281.94 0)
			(effects
				(font
					(size 1.27 1.27)
					(thickness 0.15)
				)
				(justify left bottom)
				(hide yes)
			)
		)
		(pin "1"
		)
		(pin "2"
		)
		(instances
			(project "jetson-agx-thor-baseboard"
				(path ""
					(reference "R378")
					(unit 1)
				)
			)
		)
	)
	(symbol
		(lib_id "antmicroLEDIndicationDiscrete:LED_G_0603_LTST-C190GKT")
		(at 393.7 44.45 90)
		(unit 1)
		(exclude_from_sim no)
		(in_bom yes)
		(on_board yes)
		(dnp no)
		(fields_autoplaced yes)
		(property "Reference" "D47"
			(at 395.605 40.64 90)
			(effects
				(font
					(size 1.27 1.27)
				)
				(justify right)
			)
		)
		(property "Value" "LED_G_0603_LTST-C190GKT"
			(at 401.32 21.59 0)
			(effects
				(font
					(size 1.27 1.27)
					(thickness 0.15)
				)
				(justify left bottom)
				(hide yes)
			)
		)
		(property "Footprint" "antmicro-footprints:LED_0603_1608Metric_G"
			(at 403.86 21.59 0)
			(effects
				(font
					(size 1.27 1.27)
					(thickness 0.15)
				)
				(justify left bottom)
				(hide yes)
			)
		)
		(property "Datasheet" "https://media.digikey.com/pdf/Data%20Sheets/Lite-On%20PDFs/LTST-C190GKT.pdf"
			(at 406.4 21.59 0)
			(effects
				(font
					(size 1.27 1.27)
					(thickness 0.15)
				)
				(justify left bottom)
				(hide yes)
			)
		)
		(property "Description" "LED, Green, SMD, 0603, 20 mA, 2.1 V, 569 nm"
			(at 393.7 44.45 0)
			(effects
				(font
					(size 1.27 1.27)
				)
				(hide yes)
			)
		)
		(property "MPN" "LTST-C190GKT"
			(at 408.94 21.59 0)
			(effects
				(font
					(size 1.27 1.27)
					(thickness 0.15)
				)
				(justify left bottom)
				(hide yes)
			)
		)
		(property "Manufacturer" "Lite-On"
			(at 411.48 21.59 0)
			(effects
				(font
					(size 1.27 1.27)
					(thickness 0.15)
				)
				(justify left bottom)
				(hide yes)
			)
		)
		(property "Author" "Antmicro"
			(at 414.02 21.59 0)
			(effects
				(font
					(size 1.27 1.27)
					(thickness 0.15)
				)
				(justify left bottom)
				(hide yes)
			)
		)
		(property "License" "Apache-2.0"
			(at 416.56 21.59 0)
			(effects
				(font
					(size 1.27 1.27)
					(thickness 0.15)
				)
				(justify left bottom)
				(hide yes)
			)
		)
		(property "Color" "Green"
			(at 395.605 43.18 90)
			(effects
				(font
					(size 1.27 1.27)
				)
				(justify right)
			)
		)
		(pin "1"
		)
		(pin "2"
		)
		(instances
			(project "jetson-agx-thor-baseboard"
				(path ""
					(reference "D47")
					(unit 1)
				)
			)
		)
	)
	(symbol
		(lib_id "antmicropower:+3V3")
		(at 27.94 119.38 0)
		(unit 1)
		(exclude_from_sim no)
		(in_bom yes)
		(on_board yes)
		(dnp no)
		(fields_autoplaced yes)
		(property "Reference" "#PWR0509"
			(at 43.18 119.38 0)
			(effects
				(font
					(size 1.27 1.27)
					(thickness 0.15)
				)
				(justify left bottom)
				(hide yes)
			)
		)
		(property "Value" "+3V3"
			(at 27.94 114.3 0)
			(effects
				(font
					(size 1.27 1.27)
					(thickness 0.15)
				)
			)
		)
		(property "Footprint" ""
			(at 43.18 127 0)
			(effects
				(font
					(size 1.27 1.27)
					(thickness 0.15)
				)
				(justify left bottom)
				(hide yes)
			)
		)
		(property "Datasheet" ""
			(at 43.18 129.54 0)
			(effects
				(font
					(size 1.27 1.27)
					(thickness 0.15)
				)
				(justify left bottom)
				(hide yes)
			)
		)
		(property "Description" ""
			(at 27.94 119.38 0)
			(effects
				(font
					(size 1.27 1.27)
				)
				(hide yes)
			)
		)
		(property "Author" "Antmicro"
			(at 43.18 121.92 0)
			(effects
				(font
					(size 1.27 1.27)
					(thickness 0.15)
				)
				(justify left bottom)
				(hide yes)
			)
		)
		(property "License" "Apache-2.0"
			(at 43.18 124.46 0)
			(effects
				(font
					(size 1.27 1.27)
					(thickness 0.15)
				)
				(justify left bottom)
				(hide yes)
			)
		)
		(pin "1"
		)
		(instances
			(project "jetson-agx-thor-baseboard"
				(path ""
					(reference "#PWR0509")
					(unit 1)
				)
			)
		)
	)
	(symbol
		(lib_id "antmicroCapacitors0402:C_100n_0402")
		(at 68.58 66.04 90)
		(unit 1)
		(exclude_from_sim no)
		(in_bom yes)
		(on_board yes)
		(dnp no)
		(fields_autoplaced yes)
		(property "Reference" "C89"
			(at 71.12 62.2236 90)
			(effects
				(font
					(size 1.27 1.27)
					(thickness 0.15)
				)
				(justify right)
			)
		)
		(property "Value" "C_100n_0402"
			(at 91.44 50.8 0)
			(effects
				(font
					(size 1.27 1.27)
					(thickness 0.15)
				)
				(justify left bottom)
				(hide yes)
			)
		)
		(property "Footprint" "antmicro-footprints:C_0402_1005Metric"
			(at 93.98 50.8 0)
			(effects
				(font
					(size 1.27 1.27)
					(thickness 0.15)
				)
				(justify left bottom)
				(hide yes)
			)
		)
		(property "Datasheet" "https://www.murata.com/products/productdetail?partno=GRM155R61H104KE14%23"
			(at 96.52 50.8 0)
			(effects
				(font
					(size 1.27 1.27)
					(thickness 0.15)
				)
				(justify left bottom)
				(hide yes)
			)
		)
		(property "Description" "SMD Multilayer Ceramic Capacitor, 0.1 µF, 50 V, 0402 [1005 Metric], ± 10%, X5R, GRM Series"
			(at 68.58 66.04 0)
			(effects
				(font
					(size 1.27 1.27)
				)
				(hide yes)
			)
		)
		(property "MPN" "GRM155R61H104KE14D"
			(at 99.06 50.8 0)
			(effects
				(font
					(size 1.27 1.27)
					(thickness 0.15)
				)
				(justify left bottom)
				(hide yes)
			)
		)
		(property "Val" "100n"
			(at 71.12 64.7636 90)
			(effects
				(font
					(size 1.27 1.27)
					(thickness 0.15)
				)
				(justify right)
			)
		)
		(property "Voltage" "50V"
			(at 78.74 50.8 0)
			(effects
				(font
					(size 1.27 1.27)
					(thickness 0.15)
				)
				(justify left bottom)
				(hide yes)
			)
		)
		(property "Dielectric" "X5R"
			(at 81.28 50.8 0)
			(effects
				(font
					(size 1.27 1.27)
					(thickness 0.15)
				)
				(justify left bottom)
				(hide yes)
			)
		)
		(property "Manufacturer" "Murata"
			(at 83.82 50.8 0)
			(effects
				(font
					(size 1.27 1.27)
					(thickness 0.15)
				)
				(justify left bottom)
				(hide yes)
			)
		)
		(property "License" "Apache-2.0"
			(at 86.36 50.8 0)
			(effects
				(font
					(size 1.27 1.27)
					(thickness 0.15)
				)
				(justify left bottom)
				(hide yes)
			)
		)
		(property "Author" "Antmicro"
			(at 88.9 50.8 0)
			(effects
				(font
					(size 1.27 1.27)
					(thickness 0.15)
				)
				(justify left bottom)
				(hide yes)
			)
		)
		(pin "1"
		)
		(pin "2"
		)
		(instances
			(project "jetson-agx-thor-baseboard"
				(path ""
					(reference "C89")
					(unit 1)
				)
			)
		)
	)
	(symbol
		(lib_id "antmicropower:GND")
		(at 351.79 39.37 0)
		(unit 1)
		(exclude_from_sim no)
		(in_bom yes)
		(on_board yes)
		(dnp no)
		(fields_autoplaced yes)
		(property "Reference" "#PWR0173"
			(at 351.79 45.72 0)
			(effects
				(font
					(size 1.27 1.27)
				)
				(justify left bottom)
				(hide yes)
			)
		)
		(property "Value" "GND"
			(at 351.79 43.18 0)
			(effects
				(font
					(size 1.27 1.27)
					(thickness 0.15)
				)
			)
		)
		(property "Footprint" ""
			(at 360.68 46.99 0)
			(effects
				(font
					(size 1.27 1.27)
					(thickness 0.15)
				)
				(justify left bottom)
				(hide yes)
			)
		)
		(property "Datasheet" ""
			(at 360.68 52.07 0)
			(effects
				(font
					(size 1.27 1.27)
					(thickness 0.15)
				)
				(justify left bottom)
				(hide yes)
			)
		)
		(property "Description" ""
			(at 351.79 39.37 0)
			(effects
				(font
					(size 1.27 1.27)
				)
				(hide yes)
			)
		)
		(property "Author" "Antmicro"
			(at 360.68 46.99 0)
			(effects
				(font
					(size 1.27 1.27)
					(thickness 0.15)
				)
				(justify left bottom)
				(hide yes)
			)
		)
		(property "License" "Apache-2.0"
			(at 360.68 49.53 0)
			(effects
				(font
					(size 1.27 1.27)
					(thickness 0.15)
				)
				(justify left bottom)
				(hide yes)
			)
		)
		(pin "1"
		)
		(instances
			(project "jetson-agx-thor-baseboard"
				(path ""
					(reference "#PWR0173")
					(unit 1)
				)
			)
		)
	)
	(symbol
		(lib_id "antmicroResistors0402:R_43k_0402")
		(at 210.82 101.6 0)
		(unit 1)
		(exclude_from_sim no)
		(in_bom yes)
		(on_board yes)
		(dnp no)
		(property "Reference" "R263"
			(at 213.36 96.52 0)
			(effects
				(font
					(size 1.27 1.27)
					(thickness 0.15)
				)
			)
		)
		(property "Value" "R_43k_0402"
			(at 231.14 114.3 0)
			(effects
				(font
					(size 1.27 1.27)
					(thickness 0.15)
				)
				(justify left bottom)
				(hide yes)
			)
		)
		(property "Footprint" "antmicro-footprints:R_0402_1005Metric"
			(at 231.14 116.84 0)
			(effects
				(font
					(size 1.27 1.27)
					(thickness 0.15)
				)
				(justify left bottom)
				(hide yes)
			)
		)
		(property "Datasheet" "https://www.bourns.com/docs/product-datasheets/cr.pdf"
			(at 231.14 119.38 0)
			(effects
				(font
					(size 1.27 1.27)
					(thickness 0.15)
				)
				(justify left bottom)
				(hide yes)
			)
		)
		(property "Description" "SMD Chip Resistor"
			(at 210.82 101.6 0)
			(effects
				(font
					(size 1.27 1.27)
				)
				(hide yes)
			)
		)
		(property "MPN" "CR0402-FX-4302GLF"
			(at 231.14 121.92 0)
			(effects
				(font
					(size 1.27 1.27)
					(thickness 0.15)
				)
				(justify left bottom)
				(hide yes)
			)
		)
		(property "Manufacturer" "Bourns"
			(at 231.14 124.46 0)
			(effects
				(font
					(size 1.27 1.27)
					(thickness 0.15)
				)
				(justify left bottom)
				(hide yes)
			)
		)
		(property "License" "Apache-2.0"
			(at 231.14 127 0)
			(effects
				(font
					(size 1.27 1.27)
					(thickness 0.15)
				)
				(justify left bottom)
				(hide yes)
			)
		)
		(property "Author" "Antmicro"
			(at 231.14 129.54 0)
			(effects
				(font
					(size 1.27 1.27)
					(thickness 0.15)
				)
				(justify left bottom)
				(hide yes)
			)
		)
		(property "Val" "43k"
			(at 213.36 99.06 0)
			(effects
				(font
					(size 1.27 1.27)
					(thickness 0.15)
				)
			)
		)
		(property "Tolerance" "1%"
			(at 231.14 111.76 0)
			(effects
				(font
					(size 1.27 1.27)
				)
				(justify left bottom)
				(hide yes)
			)
		)
		(pin "2"
		)
		(pin "1"
		)
		(instances
			(project "jetson-agx-thor-baseboard"
				(path ""
					(reference "R263")
					(unit 1)
				)
			)
		)
	)
	(symbol
		(lib_id "antmicroResistors0402:R_10k_0402")
		(at 207.01 256.54 90)
		(mirror x)
		(unit 1)
		(exclude_from_sim no)
		(in_bom yes)
		(on_board yes)
		(dnp no)
		(property "Reference" "R333"
			(at 200.66 257.81 90)
			(effects
				(font
					(size 1.27 1.27)
					(thickness 0.15)
				)
				(justify right)
			)
		)
		(property "Value" "R_10k_0402"
			(at 219.71 276.86 0)
			(effects
				(font
					(size 1.27 1.27)
					(thickness 0.15)
				)
				(justify left bottom)
				(hide yes)
			)
		)
		(property "Footprint" "antmicro-footprints:R_0402_1005Metric"
			(at 222.25 276.86 0)
			(effects
				(font
					(size 1.27 1.27)
					(thickness 0.15)
				)
				(justify left bottom)
				(hide yes)
			)
		)
		(property "Datasheet" "https://www.bourns.com/docs/product-datasheets/cr.pdf"
			(at 224.79 276.86 0)
			(effects
				(font
					(size 1.27 1.27)
					(thickness 0.15)
				)
				(justify left bottom)
				(hide yes)
			)
		)
		(property "Description" "SMD Chip Resistor, 10 kohm, ± 1%, 62.5 mW, 0402 [1005 Metric], Thick Film, General Purpose"
			(at 207.01 256.54 0)
			(effects
				(font
					(size 1.27 1.27)
				)
				(hide yes)
			)
		)
		(property "MPN" "CR0402-FX-1002GLF"
			(at 227.33 276.86 0)
			(effects
				(font
					(size 1.27 1.27)
					(thickness 0.15)
				)
				(justify left bottom)
				(hide yes)
			)
		)
		(property "Manufacturer" "Bourns"
			(at 229.87 276.86 0)
			(effects
				(font
					(size 1.27 1.27)
					(thickness 0.15)
				)
				(justify left bottom)
				(hide yes)
			)
		)
		(property "License" "Apache-2.0"
			(at 232.41 276.86 0)
			(effects
				(font
					(size 1.27 1.27)
					(thickness 0.15)
				)
				(justify left bottom)
				(hide yes)
			)
		)
		(property "Author" "Antmicro"
			(at 234.95 276.86 0)
			(effects
				(font
					(size 1.27 1.27)
					(thickness 0.15)
				)
				(justify left bottom)
				(hide yes)
			)
		)
		(property "Val" "10k"
			(at 201.93 260.35 90)
			(effects
				(font
					(size 1.27 1.27)
					(thickness 0.15)
				)
				(justify right)
			)
		)
		(property "Tolerance" "1%"
			(at 217.17 276.86 0)
			(effects
				(font
					(size 1.27 1.27)
				)
				(justify left bottom)
				(hide yes)
			)
		)
		(pin "2"
		)
		(pin "1"
		)
		(instances
			(project "jetson-agx-thor-baseboard"
				(path ""
					(reference "R333")
					(unit 1)
				)
			)
		)
	)
	(symbol
		(lib_id "antmicroCapacitors0402:C_100n_0402")
		(at 307.34 144.78 90)
		(mirror x)
		(unit 1)
		(exclude_from_sim no)
		(in_bom yes)
		(on_board yes)
		(dnp no)
		(fields_autoplaced yes)
		(property "Reference" "C104"
			(at 309.88 146.0563 90)
			(effects
				(font
					(size 1.27 1.27)
				)
				(justify right)
			)
		)
		(property "Value" "C_100n_0402"
			(at 317.5 165.1 0)
			(effects
				(font
					(size 1.27 1.27)
					(thickness 0.15)
				)
				(justify left bottom)
				(hide yes)
			)
		)
		(property "Footprint" "antmicro-footprints:C_0402_1005Metric"
			(at 320.04 165.1 0)
			(effects
				(font
					(size 1.27 1.27)
					(thickness 0.15)
				)
				(justify left bottom)
				(hide yes)
			)
		)
		(property "Datasheet" "https://www.murata.com/products/productdetail?partno=GRM155R61H104KE14%23"
			(at 322.58 165.1 0)
			(effects
				(font
					(size 1.27 1.27)
					(thickness 0.15)
				)
				(justify left bottom)
				(hide yes)
			)
		)
		(property "Description" "SMD Multilayer Ceramic Capacitor, 0.1 µF, 50 V, 0402 [1005 Metric], ± 10%, X5R, GRM Series"
			(at 307.34 144.78 0)
			(effects
				(font
					(size 1.27 1.27)
				)
				(hide yes)
			)
		)
		(property "Manufacturer" "Murata"
			(at 327.66 165.1 0)
			(effects
				(font
					(size 1.27 1.27)
					(thickness 0.15)
				)
				(justify left bottom)
				(hide yes)
			)
		)
		(property "MPN" "GRM155R61H104KE14D"
			(at 325.12 165.1 0)
			(effects
				(font
					(size 1.27 1.27)
					(thickness 0.15)
				)
				(justify left bottom)
				(hide yes)
			)
		)
		(property "Val" "100n"
			(at 309.88 148.5963 90)
			(effects
				(font
					(size 1.27 1.27)
					(thickness 0.15)
				)
				(justify right)
			)
		)
		(property "License" "Apache-2.0"
			(at 330.2 165.1 0)
			(effects
				(font
					(size 1.27 1.27)
					(thickness 0.15)
				)
				(justify left bottom)
				(hide yes)
			)
		)
		(property "Author" "Antmicro"
			(at 332.74 165.1 0)
			(effects
				(font
					(size 1.27 1.27)
					(thickness 0.15)
				)
				(justify left bottom)
				(hide yes)
			)
		)
		(property "Voltage" "50V"
			(at 335.28 165.1 0)
			(effects
				(font
					(size 1.27 1.27)
				)
				(justify left bottom)
				(hide yes)
			)
		)
		(property "Dielectric" "X5R"
			(at 337.82 165.1 0)
			(effects
				(font
					(size 1.27 1.27)
				)
				(justify left bottom)
				(hide yes)
			)
		)
		(pin "1"
		)
		(pin "2"
		)
		(instances
			(project "jetson-agx-thor-baseboard"
				(path ""
					(reference "C104")
					(unit 1)
				)
			)
		)
	)
	(symbol
		(lib_id "antmicroResistors0402:R_49k9_0402")
		(at 208.28 107.95 90)
		(unit 1)
		(exclude_from_sim no)
		(in_bom yes)
		(on_board yes)
		(dnp no)
		(property "Reference" "R262"
			(at 209.804 105.156 90)
			(effects
				(font
					(size 1.27 1.27)
					(thickness 0.15)
				)
				(justify right)
			)
		)
		(property "Value" "R_49k9_0402"
			(at 220.98 87.63 0)
			(effects
				(font
					(size 1.27 1.27)
					(thickness 0.15)
				)
				(justify left bottom)
				(hide yes)
			)
		)
		(property "Footprint" "antmicro-footprints:R_0402_1005Metric"
			(at 223.52 87.63 0)
			(effects
				(font
					(size 1.27 1.27)
					(thickness 0.15)
				)
				(justify left bottom)
				(hide yes)
			)
		)
		(property "Datasheet" "https://www.bourns.com/docs/product-datasheets/cr.pdf"
			(at 226.06 87.63 0)
			(effects
				(font
					(size 1.27 1.27)
					(thickness 0.15)
				)
				(justify left bottom)
				(hide yes)
			)
		)
		(property "Description" "SMD Chip Resistor, 49.9 kohm, ± 1%, 63 mW, 0402 [1005 Metric], Thick Film, General Purpose"
			(at 208.28 107.95 0)
			(effects
				(font
					(size 1.27 1.27)
				)
				(hide yes)
			)
		)
		(property "MPN" "CR0402-FX-4992GLF"
			(at 228.6 87.63 0)
			(effects
				(font
					(size 1.27 1.27)
					(thickness 0.15)
				)
				(justify left bottom)
				(hide yes)
			)
		)
		(property "Manufacturer" "Bourns"
			(at 231.14 87.63 0)
			(effects
				(font
					(size 1.27 1.27)
					(thickness 0.15)
				)
				(justify left bottom)
				(hide yes)
			)
		)
		(property "License" "Apache-2.0"
			(at 233.68 87.63 0)
			(effects
				(font
					(size 1.27 1.27)
					(thickness 0.15)
				)
				(justify left bottom)
				(hide yes)
			)
		)
		(property "Author" "Antmicro"
			(at 236.22 87.63 0)
			(effects
				(font
					(size 1.27 1.27)
					(thickness 0.15)
				)
				(justify left bottom)
				(hide yes)
			)
		)
		(property "Val" "49k9"
			(at 209.804 107.696 90)
			(effects
				(font
					(size 1.27 1.27)
					(thickness 0.15)
				)
				(justify right)
			)
		)
		(property "Tolerance" "1%"
			(at 218.44 87.63 0)
			(effects
				(font
					(size 1.27 1.27)
				)
				(justify left bottom)
				(hide yes)
			)
		)
		(pin "1"
		)
		(pin "2"
		)
		(instances
			(project "jetson-agx-thor-baseboard"
				(path ""
					(reference "R262")
					(unit 1)
				)
			)
		)
	)
	(symbol
		(lib_id "antmicroResistors0402:R_0R_0402")
		(at 187.96 161.29 0)
		(unit 1)
		(exclude_from_sim no)
		(in_bom yes)
		(on_board yes)
		(dnp no)
		(property "Reference" "R57"
			(at 193.04 160.655 0)
			(effects
				(font
					(size 1.27 1.27)
				)
				(justify left bottom)
			)
		)
		(property "Value" "R_0R_0402"
			(at 208.28 173.99 0)
			(effects
				(font
					(size 1.27 1.27)
					(thickness 0.15)
				)
				(justify left bottom)
				(hide yes)
			)
		)
		(property "Footprint" "antmicro-footprints:R_0402_1005Metric"
			(at 208.28 176.53 0)
			(effects
				(font
					(size 1.27 1.27)
					(thickness 0.15)
				)
				(justify left bottom)
				(hide yes)
			)
		)
		(property "Datasheet" "https://industrial.panasonic.com/cdbs/www-data/pdf/RDA0000/AOA0000C301.pdf"
			(at 208.28 179.07 0)
			(effects
				(font
					(size 1.27 1.27)
					(thickness 0.15)
				)
				(justify left bottom)
				(hide yes)
			)
		)
		(property "Description" "SMD Chip Resistor, Jumper, 0 ohm, 100 mW, 0402 [1005 Metric], Thick Film, General Purpose"
			(at 187.96 161.29 0)
			(effects
				(font
					(size 1.27 1.27)
				)
				(hide yes)
			)
		)
		(property "Manufacturer" "Panasonic"
			(at 208.28 184.15 0)
			(effects
				(font
					(size 1.27 1.27)
					(thickness 0.15)
				)
				(justify left bottom)
				(hide yes)
			)
		)
		(property "MPN" "ERJ2GE0R00X"
			(at 208.28 181.61 0)
			(effects
				(font
					(size 1.27 1.27)
					(thickness 0.15)
				)
				(justify left bottom)
				(hide yes)
			)
		)
		(property "Val" "0R"
			(at 185.42 160.655 0)
			(effects
				(font
					(size 1.27 1.27)
					(thickness 0.15)
				)
				(justify left bottom)
			)
		)
		(property "License" "Apache-2.0"
			(at 208.28 186.69 0)
			(effects
				(font
					(size 1.27 1.27)
					(thickness 0.15)
				)
				(justify left bottom)
				(hide yes)
			)
		)
		(property "Author" "Antmicro"
			(at 208.28 189.23 0)
			(effects
				(font
					(size 1.27 1.27)
					(thickness 0.15)
				)
				(justify left bottom)
				(hide yes)
			)
		)
		(property "Tolerance" "~"
			(at 208.28 171.45 0)
			(effects
				(font
					(size 1.27 1.27)
				)
				(justify left bottom)
				(hide yes)
			)
		)
		(property "Current" "1A"
			(at 208.28 191.77 0)
			(effects
				(font
					(size 1.27 1.27)
					(thickness 0.15)
				)
				(justify left bottom)
				(hide yes)
			)
		)
		(pin "1"
		)
		(pin "2"
		)
		(instances
			(project "jetson-agx-thor-baseboard"
				(path ""
					(reference "R57")
					(unit 1)
				)
			)
		)
	)
	(symbol
		(lib_id "antmicroCapacitors0402:C_100n_0402")
		(at 289.56 91.44 180)
		(unit 1)
		(exclude_from_sim no)
		(in_bom yes)
		(on_board yes)
		(dnp no)
		(property "Reference" "C112"
			(at 293.37 89.408 0)
			(effects
				(font
					(size 1.27 1.27)
				)
				(justify left bottom)
			)
		)
		(property "Value" "C_100n_0402"
			(at 269.24 81.28 0)
			(effects
				(font
					(size 1.27 1.27)
					(thickness 0.15)
				)
				(justify left bottom)
				(hide yes)
			)
		)
		(property "Footprint" "antmicro-footprints:C_0402_1005Metric"
			(at 269.24 78.74 0)
			(effects
				(font
					(size 1.27 1.27)
					(thickness 0.15)
				)
				(justify left bottom)
				(hide yes)
			)
		)
		(property "Datasheet" "https://www.murata.com/products/productdetail?partno=GRM155R61H104KE14%23"
			(at 269.24 76.2 0)
			(effects
				(font
					(size 1.27 1.27)
					(thickness 0.15)
				)
				(justify left bottom)
				(hide yes)
			)
		)
		(property "Description" "SMD Multilayer Ceramic Capacitor, 0.1 µF, 50 V, 0402 [1005 Metric], ± 10%, X5R, GRM Series"
			(at 289.56 91.44 0)
			(effects
				(font
					(size 1.27 1.27)
				)
				(hide yes)
			)
		)
		(property "Manufacturer" "Murata"
			(at 269.24 71.12 0)
			(effects
				(font
					(size 1.27 1.27)
					(thickness 0.15)
				)
				(justify left bottom)
				(hide yes)
			)
		)
		(property "MPN" "GRM155R61H104KE14D"
			(at 269.24 73.66 0)
			(effects
				(font
					(size 1.27 1.27)
					(thickness 0.15)
				)
				(justify left bottom)
				(hide yes)
			)
		)
		(property "Val" "100n"
			(at 285.75 92.075 0)
			(effects
				(font
					(size 1.27 1.27)
					(thickness 0.15)
				)
				(justify left bottom)
			)
		)
		(property "License" "Apache-2.0"
			(at 269.24 68.58 0)
			(effects
				(font
					(size 1.27 1.27)
					(thickness 0.15)
				)
				(justify left bottom)
				(hide yes)
			)
		)
		(property "Author" "Antmicro"
			(at 269.24 66.04 0)
			(effects
				(font
					(size 1.27 1.27)
					(thickness 0.15)
				)
				(justify left bottom)
				(hide yes)
			)
		)
		(property "Voltage" "50V"
			(at 269.24 63.5 0)
			(effects
				(font
					(size 1.27 1.27)
				)
				(justify left bottom)
				(hide yes)
			)
		)
		(property "Dielectric" "X5R"
			(at 269.24 60.96 0)
			(effects
				(font
					(size 1.27 1.27)
				)
				(justify left bottom)
				(hide yes)
			)
		)
		(pin "1"
		)
		(pin "2"
		)
		(instances
			(project "jetson-agx-thor-baseboard"
				(path ""
					(reference "C112")
					(unit 1)
				)
			)
		)
	)
	(symbol
		(lib_id "antmicroTVSDiodes:TPD4E05U06QDQARQ1")
		(at 341.63 232.41 270)
		(unit 1)
		(exclude_from_sim no)
		(in_bom yes)
		(on_board yes)
		(dnp no)
		(property "Reference" "U19"
			(at 335.788 243.332 90)
			(effects
				(font
					(size 1.27 1.27)
				)
				(justify right)
			)
		)
		(property "Value" "TPD4E05U06QDQARQ1"
			(at 331.47 256.54 0)
			(effects
				(font
					(size 1.27 1.27)
					(thickness 0.15)
				)
				(justify left bottom)
				(hide yes)
			)
		)
		(property "Footprint" "antmicro-footprints:USON-10_2.5x1mm_P0.5mm"
			(at 336.55 256.54 0)
			(effects
				(font
					(size 1.27 1.27)
					(thickness 0.15)
				)
				(justify left bottom)
				(hide yes)
			)
		)
		(property "Datasheet" "https://www.ti.com/lit/ds/symlink/tpd4e05u06-q1.pdf?HQS=dis-mous-null-mousermode-dsf-pf-null-wwe&ts=1663591265741&ref_url=https%253A%252F%252Fwww.mouser.com%252F"
			(at 334.01 256.54 0)
			(effects
				(font
					(size 1.27 1.27)
					(thickness 0.15)
				)
				(justify left bottom)
				(hide yes)
			)
		)
		(property "Description" "TVS diode array, 12 kV, USON-10, 5.5 V, 0.5 pF"
			(at 341.63 232.41 0)
			(effects
				(font
					(size 1.27 1.27)
				)
				(hide yes)
			)
		)
		(property "Manufacturer" "Texas Instruments"
			(at 328.93 256.54 0)
			(effects
				(font
					(size 1.27 1.27)
					(thickness 0.15)
				)
				(justify left bottom)
				(hide yes)
			)
		)
		(property "MPN" "TPD4E05U06QDQARQ1"
			(at 344.424 246.126 90)
			(effects
				(font
					(size 1.27 1.27)
					(thickness 0.15)
				)
				(justify right)
			)
		)
		(property "Author" "Antmicro"
			(at 326.39 256.54 0)
			(effects
				(font
					(size 1.27 1.27)
					(thickness 0.15)
				)
				(justify left bottom)
				(hide yes)
			)
		)
		(property "License" "Apache-2.0"
			(at 323.85 256.54 0)
			(effects
				(font
					(size 1.27 1.27)
					(thickness 0.15)
				)
				(justify left bottom)
				(hide yes)
			)
		)
		(pin "1"
		)
		(pin "10"
		)
		(pin "2"
		)
		(pin "3"
		)
		(pin "4"
		)
		(pin "5"
		)
		(pin "6"
		)
		(pin "7"
		)
		(pin "8"
		)
		(pin "9"
		)
		(instances
			(project "jetson-agx-thor-baseboard"
				(path ""
					(reference "U19")
					(unit 1)
				)
			)
		)
	)
	(symbol
		(lib_id "antmicropower:GND")
		(at 350.52 161.29 0)
		(unit 1)
		(exclude_from_sim no)
		(in_bom yes)
		(on_board yes)
		(dnp no)
		(fields_autoplaced yes)
		(property "Reference" "#PWR0209"
			(at 350.52 167.64 0)
			(effects
				(font
					(size 1.27 1.27)
				)
				(justify left bottom)
				(hide yes)
			)
		)
		(property "Value" "GND"
			(at 350.52 165.1 0)
			(effects
				(font
					(size 1.27 1.27)
					(thickness 0.15)
				)
			)
		)
		(property "Footprint" ""
			(at 359.41 168.91 0)
			(effects
				(font
					(size 1.27 1.27)
					(thickness 0.15)
				)
				(justify left bottom)
				(hide yes)
			)
		)
		(property "Datasheet" ""
			(at 359.41 173.99 0)
			(effects
				(font
					(size 1.27 1.27)
					(thickness 0.15)
				)
				(justify left bottom)
				(hide yes)
			)
		)
		(property "Description" ""
			(at 350.52 161.29 0)
			(effects
				(font
					(size 1.27 1.27)
				)
				(hide yes)
			)
		)
		(property "Author" "Antmicro"
			(at 359.41 168.91 0)
			(effects
				(font
					(size 1.27 1.27)
					(thickness 0.15)
				)
				(justify left bottom)
				(hide yes)
			)
		)
		(property "License" "Apache-2.0"
			(at 359.41 171.45 0)
			(effects
				(font
					(size 1.27 1.27)
					(thickness 0.15)
				)
				(justify left bottom)
				(hide yes)
			)
		)
		(pin "1"
		)
		(instances
			(project "jetson-agx-thor-baseboard"
				(path ""
					(reference "#PWR0209")
					(unit 1)
				)
			)
		)
	)
	(symbol
		(lib_id "antmicroCapacitors0603:C_22u_16V_0603")
		(at 17.78 48.26 90)
		(unit 1)
		(exclude_from_sim no)
		(in_bom yes)
		(on_board yes)
		(dnp no)
		(fields_autoplaced yes)
		(property "Reference" "C311"
			(at 20.32 44.4435 90)
			(effects
				(font
					(size 1.27 1.27)
				)
				(justify right)
			)
		)
		(property "Value" "C_22u_16V_0603"
			(at 27.94 27.94 0)
			(effects
				(font
					(size 1.27 1.27)
					(thickness 0.15)
				)
				(justify left bottom)
				(hide yes)
			)
		)
		(property "Footprint" "antmicro-footprints:C_0603_1608Metric_EIA"
			(at 30.48 27.94 0)
			(effects
				(font
					(size 1.27 1.27)
					(thickness 0.15)
				)
				(justify left bottom)
				(hide yes)
			)
		)
		(property "Datasheet" "https://product.samsungsem.com/mlcc/CL10A226MO7JZN.do"
			(at 33.02 27.94 0)
			(effects
				(font
					(size 1.27 1.27)
					(thickness 0.15)
				)
				(justify left bottom)
				(hide yes)
			)
		)
		(property "Description" "SMD Multilayer Ceramic Capacitor"
			(at 17.78 48.26 0)
			(effects
				(font
					(size 1.27 1.27)
				)
				(hide yes)
			)
		)
		(property "Manufacturer" "Samsung Electro-Mechanics"
			(at 38.1 27.94 0)
			(effects
				(font
					(size 1.27 1.27)
					(thickness 0.15)
				)
				(justify left bottom)
				(hide yes)
			)
		)
		(property "MPN" "CL10A226MO7JZNC"
			(at 35.56 27.94 0)
			(effects
				(font
					(size 1.27 1.27)
					(thickness 0.15)
				)
				(justify left bottom)
				(hide yes)
			)
		)
		(property "Val" "22u"
			(at 20.32 46.9836 90)
			(effects
				(font
					(size 1.27 1.27)
					(thickness 0.15)
				)
				(justify right)
			)
		)
		(property "License" "Apache-2.0"
			(at 40.64 27.94 0)
			(effects
				(font
					(size 1.27 1.27)
					(thickness 0.15)
				)
				(justify left bottom)
				(hide yes)
			)
		)
		(property "Author" "Antmicro"
			(at 43.18 27.94 0)
			(effects
				(font
					(size 1.27 1.27)
					(thickness 0.15)
				)
				(justify left bottom)
				(hide yes)
			)
		)
		(property "Voltage" "16V"
			(at 45.72 27.94 0)
			(effects
				(font
					(size 1.27 1.27)
				)
				(justify left bottom)
				(hide yes)
			)
		)
		(property "Dielectric" ""
			(at 48.26 27.94 0)
			(effects
				(font
					(size 1.27 1.27)
				)
				(justify left bottom)
				(hide yes)
			)
		)
		(pin "1"
		)
		(pin "2"
		)
		(instances
			(project "jetson-agx-thor-baseboard"
				(path ""
					(reference "C311")
					(unit 1)
				)
			)
		)
	)
	(symbol
		(lib_id "antmicropower:+3V3")
		(at 27.94 87.63 0)
		(unit 1)
		(exclude_from_sim no)
		(in_bom yes)
		(on_board yes)
		(dnp no)
		(property "Reference" "#PWR0168"
			(at 43.18 87.63 0)
			(effects
				(font
					(size 1.27 1.27)
					(thickness 0.15)
				)
				(justify left bottom)
				(hide yes)
			)
		)
		(property "Value" "+3V3"
			(at 27.94 84.074 0)
			(effects
				(font
					(size 1.27 1.27)
					(thickness 0.15)
				)
			)
		)
		(property "Footprint" ""
			(at 43.18 95.25 0)
			(effects
				(font
					(size 1.27 1.27)
					(thickness 0.15)
				)
				(justify left bottom)
				(hide yes)
			)
		)
		(property "Datasheet" ""
			(at 43.18 97.79 0)
			(effects
				(font
					(size 1.27 1.27)
					(thickness 0.15)
				)
				(justify left bottom)
				(hide yes)
			)
		)
		(property "Description" ""
			(at 27.94 87.63 0)
			(effects
				(font
					(size 1.27 1.27)
				)
				(hide yes)
			)
		)
		(property "Author" "Antmicro"
			(at 43.18 90.17 0)
			(effects
				(font
					(size 1.27 1.27)
					(thickness 0.15)
				)
				(justify left bottom)
				(hide yes)
			)
		)
		(property "License" "Apache-2.0"
			(at 43.18 92.71 0)
			(effects
				(font
					(size 1.27 1.27)
					(thickness 0.15)
				)
				(justify left bottom)
				(hide yes)
			)
		)
		(pin "1"
		)
		(instances
			(project "jetson-agx-thor-baseboard"
				(path ""
					(reference "#PWR0168")
					(unit 1)
				)
			)
		)
	)
	(symbol
		(lib_id "antmicroCapacitors0402:C_100n_0402")
		(at 361.95 33.02 90)
		(mirror x)
		(unit 1)
		(exclude_from_sim no)
		(in_bom yes)
		(on_board yes)
		(dnp no)
		(fields_autoplaced yes)
		(property "Reference" "C80"
			(at 364.49 34.2963 90)
			(effects
				(font
					(size 1.27 1.27)
				)
				(justify right)
			)
		)
		(property "Value" "C_100n_0402"
			(at 372.11 53.34 0)
			(effects
				(font
					(size 1.27 1.27)
					(thickness 0.15)
				)
				(justify left bottom)
				(hide yes)
			)
		)
		(property "Footprint" "antmicro-footprints:C_0402_1005Metric"
			(at 374.65 53.34 0)
			(effects
				(font
					(size 1.27 1.27)
					(thickness 0.15)
				)
				(justify left bottom)
				(hide yes)
			)
		)
		(property "Datasheet" "https://www.murata.com/products/productdetail?partno=GRM155R61H104KE14%23"
			(at 377.19 53.34 0)
			(effects
				(font
					(size 1.27 1.27)
					(thickness 0.15)
				)
				(justify left bottom)
				(hide yes)
			)
		)
		(property "Description" "SMD Multilayer Ceramic Capacitor, 0.1 µF, 50 V, 0402 [1005 Metric], ± 10%, X5R, GRM Series"
			(at 361.95 33.02 0)
			(effects
				(font
					(size 1.27 1.27)
				)
				(hide yes)
			)
		)
		(property "Manufacturer" "Murata"
			(at 382.27 53.34 0)
			(effects
				(font
					(size 1.27 1.27)
					(thickness 0.15)
				)
				(justify left bottom)
				(hide yes)
			)
		)
		(property "MPN" "GRM155R61H104KE14D"
			(at 379.73 53.34 0)
			(effects
				(font
					(size 1.27 1.27)
					(thickness 0.15)
				)
				(justify left bottom)
				(hide yes)
			)
		)
		(property "Val" "100n"
			(at 364.49 36.8363 90)
			(effects
				(font
					(size 1.27 1.27)
					(thickness 0.15)
				)
				(justify right)
			)
		)
		(property "License" "Apache-2.0"
			(at 384.81 53.34 0)
			(effects
				(font
					(size 1.27 1.27)
					(thickness 0.15)
				)
				(justify left bottom)
				(hide yes)
			)
		)
		(property "Author" "Antmicro"
			(at 387.35 53.34 0)
			(effects
				(font
					(size 1.27 1.27)
					(thickness 0.15)
				)
				(justify left bottom)
				(hide yes)
			)
		)
		(property "Voltage" "50V"
			(at 389.89 53.34 0)
			(effects
				(font
					(size 1.27 1.27)
				)
				(justify left bottom)
				(hide yes)
			)
		)
		(property "Dielectric" "X5R"
			(at 392.43 53.34 0)
			(effects
				(font
					(size 1.27 1.27)
				)
				(justify left bottom)
				(hide yes)
			)
		)
		(pin "1"
		)
		(pin "2"
		)
		(instances
			(project "jetson-agx-thor-baseboard"
				(path ""
					(reference "C80")
					(unit 1)
				)
			)
		)
	)
	(symbol
		(lib_id "antmicropower:GND")
		(at 114.3 189.23 0)
		(mirror y)
		(unit 1)
		(exclude_from_sim no)
		(in_bom yes)
		(on_board yes)
		(dnp no)
		(property "Reference" "#PWR0196"
			(at 114.3 195.58 0)
			(effects
				(font
					(size 1.27 1.27)
				)
				(justify left bottom)
				(hide yes)
			)
		)
		(property "Value" "GND"
			(at 114.3 193.04 0)
			(effects
				(font
					(size 1.27 1.27)
					(thickness 0.15)
				)
			)
		)
		(property "Footprint" ""
			(at 105.41 196.85 0)
			(effects
				(font
					(size 1.27 1.27)
					(thickness 0.15)
				)
				(justify left bottom)
				(hide yes)
			)
		)
		(property "Datasheet" ""
			(at 105.41 201.93 0)
			(effects
				(font
					(size 1.27 1.27)
					(thickness 0.15)
				)
				(justify left bottom)
				(hide yes)
			)
		)
		(property "Description" ""
			(at 114.3 189.23 0)
			(effects
				(font
					(size 1.27 1.27)
				)
				(hide yes)
			)
		)
		(property "Author" "Antmicro"
			(at 105.41 196.85 0)
			(effects
				(font
					(size 1.27 1.27)
					(thickness 0.15)
				)
				(justify left bottom)
				(hide yes)
			)
		)
		(property "License" "Apache-2.0"
			(at 105.41 199.39 0)
			(effects
				(font
					(size 1.27 1.27)
					(thickness 0.15)
				)
				(justify left bottom)
				(hide yes)
			)
		)
		(pin "1"
		)
		(instances
			(project "jetson-agx-thor-baseboard"
				(path ""
					(reference "#PWR0196")
					(unit 1)
				)
			)
		)
	)
	(symbol
		(lib_id "antmicroTVSDiodes:TPD4E05U06QDQARQ1")
		(at 322.58 110.49 270)
		(unit 1)
		(exclude_from_sim no)
		(in_bom yes)
		(on_board yes)
		(dnp no)
		(property "Reference" "U27"
			(at 311.912 121.666 90)
			(effects
				(font
					(size 1.27 1.27)
				)
			)
		)
		(property "Value" "TPD4E05U06QDQARQ1"
			(at 312.42 134.62 0)
			(effects
				(font
					(size 1.27 1.27)
					(thickness 0.15)
				)
				(justify left bottom)
				(hide yes)
			)
		)
		(property "Footprint" "antmicro-footprints:USON-10_2.5x1mm_P0.5mm"
			(at 317.5 134.62 0)
			(effects
				(font
					(size 1.27 1.27)
					(thickness 0.15)
				)
				(justify left bottom)
				(hide yes)
			)
		)
		(property "Datasheet" "https://www.ti.com/lit/ds/symlink/tpd4e05u06-q1.pdf?HQS=dis-mous-null-mousermode-dsf-pf-null-wwe&ts=1663591265741&ref_url=https%253A%252F%252Fwww.mouser.com%252F"
			(at 314.96 134.62 0)
			(effects
				(font
					(size 1.27 1.27)
					(thickness 0.15)
				)
				(justify left bottom)
				(hide yes)
			)
		)
		(property "Description" "TVS diode array, 12 kV, USON-10, 5.5 V, 0.5 pF"
			(at 322.58 110.49 0)
			(effects
				(font
					(size 1.27 1.27)
				)
				(hide yes)
			)
		)
		(property "Manufacturer" "Texas Instruments"
			(at 309.88 134.62 0)
			(effects
				(font
					(size 1.27 1.27)
					(thickness 0.15)
				)
				(justify left bottom)
				(hide yes)
			)
		)
		(property "MPN" "TPD4E05U06QDQARQ1"
			(at 311.912 124.206 90)
			(effects
				(font
					(size 1.27 1.27)
					(thickness 0.15)
				)
			)
		)
		(property "Author" "Antmicro"
			(at 307.34 134.62 0)
			(effects
				(font
					(size 1.27 1.27)
					(thickness 0.15)
				)
				(justify left bottom)
				(hide yes)
			)
		)
		(property "License" "Apache-2.0"
			(at 304.8 134.62 0)
			(effects
				(font
					(size 1.27 1.27)
					(thickness 0.15)
				)
				(justify left bottom)
				(hide yes)
			)
		)
		(pin "1"
		)
		(pin "10"
		)
		(pin "2"
		)
		(pin "3"
		)
		(pin "4"
		)
		(pin "5"
		)
		(pin "6"
		)
		(pin "7"
		)
		(pin "8"
		)
		(pin "9"
		)
		(instances
			(project "jetson-agx-thor-baseboard"
				(path ""
					(reference "U27")
					(unit 1)
				)
			)
		)
	)
	(symbol
		(lib_id "antmicroDiodesRectifiersSingle:RB521S30T1G")
		(at 231.14 255.27 180)
		(unit 1)
		(exclude_from_sim no)
		(in_bom yes)
		(on_board yes)
		(dnp no)
		(property "Reference" "D60"
			(at 229.108 248.92 0)
			(effects
				(font
					(size 1.27 1.27)
				)
			)
		)
		(property "Value" "RB521S30T1G"
			(at 208.28 240.03 0)
			(effects
				(font
					(size 1.27 1.27)
					(thickness 0.15)
				)
				(justify left bottom)
				(hide yes)
			)
		)
		(property "Footprint" "antmicro-footprints:SOD-523"
			(at 208.28 245.11 0)
			(effects
				(font
					(size 1.27 1.27)
					(thickness 0.15)
				)
				(justify left bottom)
				(hide yes)
			)
		)
		(property "Datasheet" "https://www.onsemi.com/pdf/datasheet/rb521s30t1-d.pdf"
			(at 208.28 242.57 0)
			(effects
				(font
					(size 1.27 1.27)
					(thickness 0.15)
				)
				(justify left bottom)
				(hide yes)
			)
		)
		(property "Description" "Small Signal Schottky Diode, Single, 30 V, 200 mA, 500 mV, 1 A, 125 °C"
			(at 231.14 255.27 0)
			(effects
				(font
					(size 1.27 1.27)
				)
				(hide yes)
			)
		)
		(property "MPN" "RB521S30T1G"
			(at 229.108 251.46 0)
			(effects
				(font
					(size 1.27 1.27)
					(thickness 0.15)
				)
			)
		)
		(property "Manufacturer" "ON Semiconductor"
			(at 208.28 237.49 0)
			(effects
				(font
					(size 1.27 1.27)
					(thickness 0.15)
				)
				(justify left bottom)
				(hide yes)
			)
		)
		(property "Author" "Antmicro"
			(at 208.28 234.95 0)
			(effects
				(font
					(size 1.27 1.27)
					(thickness 0.15)
				)
				(justify left bottom)
				(hide yes)
			)
		)
		(property "License" "Apache-2.0"
			(at 208.28 232.41 0)
			(effects
				(font
					(size 1.27 1.27)
					(thickness 0.15)
				)
				(justify left bottom)
				(hide yes)
			)
		)
		(pin "1"
		)
		(pin "2"
		)
		(instances
			(project "jetson-agx-thor-baseboard"
				(path ""
					(reference "D60")
					(unit 1)
				)
			)
		)
	)
	(symbol
		(lib_id "antmicropower:GND")
		(at 91.44 257.81 0)
		(unit 1)
		(exclude_from_sim no)
		(in_bom yes)
		(on_board yes)
		(dnp no)
		(property "Reference" "#PWR0202"
			(at 91.44 264.16 0)
			(effects
				(font
					(size 1.27 1.27)
				)
				(justify left bottom)
				(hide yes)
			)
		)
		(property "Value" "GND"
			(at 91.44 261.62 0)
			(effects
				(font
					(size 1.27 1.27)
					(thickness 0.15)
				)
			)
		)
		(property "Footprint" ""
			(at 100.33 265.43 0)
			(effects
				(font
					(size 1.27 1.27)
					(thickness 0.15)
				)
				(justify left bottom)
				(hide yes)
			)
		)
		(property "Datasheet" ""
			(at 100.33 270.51 0)
			(effects
				(font
					(size 1.27 1.27)
					(thickness 0.15)
				)
				(justify left bottom)
				(hide yes)
			)
		)
		(property "Description" ""
			(at 91.44 257.81 0)
			(effects
				(font
					(size 1.27 1.27)
				)
				(hide yes)
			)
		)
		(property "Author" "Antmicro"
			(at 100.33 265.43 0)
			(effects
				(font
					(size 1.27 1.27)
					(thickness 0.15)
				)
				(justify left bottom)
				(hide yes)
			)
		)
		(property "License" "Apache-2.0"
			(at 100.33 267.97 0)
			(effects
				(font
					(size 1.27 1.27)
					(thickness 0.15)
				)
				(justify left bottom)
				(hide yes)
			)
		)
		(pin "1"
		)
		(instances
			(project "jetson-agx-thor-baseboard"
				(path ""
					(reference "#PWR0202")
					(unit 1)
				)
			)
		)
	)
	(symbol
		(lib_id "antmicroResistors0402:R_43k_0402")
		(at 210.82 63.5 0)
		(unit 1)
		(exclude_from_sim no)
		(in_bom yes)
		(on_board yes)
		(dnp no)
		(property "Reference" "R261"
			(at 213.36 58.42 0)
			(effects
				(font
					(size 1.27 1.27)
					(thickness 0.15)
				)
			)
		)
		(property "Value" "R_43k_0402"
			(at 231.14 76.2 0)
			(effects
				(font
					(size 1.27 1.27)
					(thickness 0.15)
				)
				(justify left bottom)
				(hide yes)
			)
		)
		(property "Footprint" "antmicro-footprints:R_0402_1005Metric"
			(at 231.14 78.74 0)
			(effects
				(font
					(size 1.27 1.27)
					(thickness 0.15)
				)
				(justify left bottom)
				(hide yes)
			)
		)
		(property "Datasheet" "https://www.bourns.com/docs/product-datasheets/cr.pdf"
			(at 231.14 81.28 0)
			(effects
				(font
					(size 1.27 1.27)
					(thickness 0.15)
				)
				(justify left bottom)
				(hide yes)
			)
		)
		(property "Description" "SMD Chip Resistor"
			(at 210.82 63.5 0)
			(effects
				(font
					(size 1.27 1.27)
				)
				(hide yes)
			)
		)
		(property "MPN" "CR0402-FX-4302GLF"
			(at 231.14 83.82 0)
			(effects
				(font
					(size 1.27 1.27)
					(thickness 0.15)
				)
				(justify left bottom)
				(hide yes)
			)
		)
		(property "Manufacturer" "Bourns"
			(at 231.14 86.36 0)
			(effects
				(font
					(size 1.27 1.27)
					(thickness 0.15)
				)
				(justify left bottom)
				(hide yes)
			)
		)
		(property "License" "Apache-2.0"
			(at 231.14 88.9 0)
			(effects
				(font
					(size 1.27 1.27)
					(thickness 0.15)
				)
				(justify left bottom)
				(hide yes)
			)
		)
		(property "Author" "Antmicro"
			(at 231.14 91.44 0)
			(effects
				(font
					(size 1.27 1.27)
					(thickness 0.15)
				)
				(justify left bottom)
				(hide yes)
			)
		)
		(property "Val" "43k"
			(at 213.36 60.96 0)
			(effects
				(font
					(size 1.27 1.27)
					(thickness 0.15)
				)
			)
		)
		(property "Tolerance" "1%"
			(at 231.14 73.66 0)
			(effects
				(font
					(size 1.27 1.27)
				)
				(justify left bottom)
				(hide yes)
			)
		)
		(pin "2"
		)
		(pin "1"
		)
		(instances
			(project ""
				(path ""
					(reference "R261")
					(unit 1)
				)
			)
		)
	)
	(symbol
		(lib_id "antmicroCapacitors0402:C_100n_0402")
		(at 109.22 48.26 90)
		(unit 1)
		(exclude_from_sim no)
		(in_bom yes)
		(on_board yes)
		(dnp no)
		(fields_autoplaced yes)
		(property "Reference" "C100"
			(at 111.76 44.4436 90)
			(effects
				(font
					(size 1.27 1.27)
					(thickness 0.15)
				)
				(justify right)
			)
		)
		(property "Value" "C_100n_0402"
			(at 132.08 33.02 0)
			(effects
				(font
					(size 1.27 1.27)
					(thickness 0.15)
				)
				(justify left bottom)
				(hide yes)
			)
		)
		(property "Footprint" "antmicro-footprints:C_0402_1005Metric"
			(at 134.62 33.02 0)
			(effects
				(font
					(size 1.27 1.27)
					(thickness 0.15)
				)
				(justify left bottom)
				(hide yes)
			)
		)
		(property "Datasheet" "https://www.murata.com/products/productdetail?partno=GRM155R61H104KE14%23"
			(at 137.16 33.02 0)
			(effects
				(font
					(size 1.27 1.27)
					(thickness 0.15)
				)
				(justify left bottom)
				(hide yes)
			)
		)
		(property "Description" "SMD Multilayer Ceramic Capacitor, 0.1 µF, 50 V, 0402 [1005 Metric], ± 10%, X5R, GRM Series"
			(at 109.22 48.26 0)
			(effects
				(font
					(size 1.27 1.27)
				)
				(hide yes)
			)
		)
		(property "MPN" "GRM155R61H104KE14D"
			(at 139.7 33.02 0)
			(effects
				(font
					(size 1.27 1.27)
					(thickness 0.15)
				)
				(justify left bottom)
				(hide yes)
			)
		)
		(property "Val" "100n"
			(at 111.76 46.9836 90)
			(effects
				(font
					(size 1.27 1.27)
					(thickness 0.15)
				)
				(justify right)
			)
		)
		(property "Voltage" "50V"
			(at 119.38 33.02 0)
			(effects
				(font
					(size 1.27 1.27)
					(thickness 0.15)
				)
				(justify left bottom)
				(hide yes)
			)
		)
		(property "Dielectric" "X5R"
			(at 121.92 33.02 0)
			(effects
				(font
					(size 1.27 1.27)
					(thickness 0.15)
				)
				(justify left bottom)
				(hide yes)
			)
		)
		(property "Manufacturer" "Murata"
			(at 124.46 33.02 0)
			(effects
				(font
					(size 1.27 1.27)
					(thickness 0.15)
				)
				(justify left bottom)
				(hide yes)
			)
		)
		(property "License" "Apache-2.0"
			(at 127 33.02 0)
			(effects
				(font
					(size 1.27 1.27)
					(thickness 0.15)
				)
				(justify left bottom)
				(hide yes)
			)
		)
		(property "Author" "Antmicro"
			(at 129.54 33.02 0)
			(effects
				(font
					(size 1.27 1.27)
					(thickness 0.15)
				)
				(justify left bottom)
				(hide yes)
			)
		)
		(pin "1"
		)
		(pin "2"
		)
		(instances
			(project "jetson-agx-thor-baseboard"
				(path ""
					(reference "C100")
					(unit 1)
				)
			)
		)
	)
	(symbol
		(lib_id "antmicroCapacitors0402:C_100n_0402")
		(at 289.56 106.68 180)
		(unit 1)
		(exclude_from_sim no)
		(in_bom yes)
		(on_board yes)
		(dnp no)
		(property "Reference" "C113"
			(at 293.37 104.648 0)
			(effects
				(font
					(size 1.27 1.27)
				)
				(justify left bottom)
			)
		)
		(property "Value" "C_100n_0402"
			(at 269.24 96.52 0)
			(effects
				(font
					(size 1.27 1.27)
					(thickness 0.15)
				)
				(justify left bottom)
				(hide yes)
			)
		)
		(property "Footprint" "antmicro-footprints:C_0402_1005Metric"
			(at 269.24 93.98 0)
			(effects
				(font
					(size 1.27 1.27)
					(thickness 0.15)
				)
				(justify left bottom)
				(hide yes)
			)
		)
		(property "Datasheet" "https://www.murata.com/products/productdetail?partno=GRM155R61H104KE14%23"
			(at 269.24 91.44 0)
			(effects
				(font
					(size 1.27 1.27)
					(thickness 0.15)
				)
				(justify left bottom)
				(hide yes)
			)
		)
		(property "Description" "SMD Multilayer Ceramic Capacitor, 0.1 µF, 50 V, 0402 [1005 Metric], ± 10%, X5R, GRM Series"
			(at 289.56 106.68 0)
			(effects
				(font
					(size 1.27 1.27)
				)
				(hide yes)
			)
		)
		(property "Manufacturer" "Murata"
			(at 269.24 86.36 0)
			(effects
				(font
					(size 1.27 1.27)
					(thickness 0.15)
				)
				(justify left bottom)
				(hide yes)
			)
		)
		(property "MPN" "GRM155R61H104KE14D"
			(at 269.24 88.9 0)
			(effects
				(font
					(size 1.27 1.27)
					(thickness 0.15)
				)
				(justify left bottom)
				(hide yes)
			)
		)
		(property "Val" "100n"
			(at 285.75 107.315 0)
			(effects
				(font
					(size 1.27 1.27)
					(thickness 0.15)
				)
				(justify left bottom)
			)
		)
		(property "License" "Apache-2.0"
			(at 269.24 83.82 0)
			(effects
				(font
					(size 1.27 1.27)
					(thickness 0.15)
				)
				(justify left bottom)
				(hide yes)
			)
		)
		(property "Author" "Antmicro"
			(at 269.24 81.28 0)
			(effects
				(font
					(size 1.27 1.27)
					(thickness 0.15)
				)
				(justify left bottom)
				(hide yes)
			)
		)
		(property "Voltage" "50V"
			(at 269.24 78.74 0)
			(effects
				(font
					(size 1.27 1.27)
				)
				(justify left bottom)
				(hide yes)
			)
		)
		(property "Dielectric" "X5R"
			(at 269.24 76.2 0)
			(effects
				(font
					(size 1.27 1.27)
				)
				(justify left bottom)
				(hide yes)
			)
		)
		(pin "1"
		)
		(pin "2"
		)
		(instances
			(project "jetson-agx-thor-baseboard"
				(path ""
					(reference "C113")
					(unit 1)
				)
			)
		)
	)
	(symbol
		(lib_id "antmicroTestPoints:TP_0.75mm_SMD")
		(at 114.3 132.08 180)
		(unit 1)
		(exclude_from_sim no)
		(in_bom no)
		(on_board yes)
		(dnp no)
		(property "Reference" "TP1"
			(at 110.236 131.318 0)
			(effects
				(font
					(size 1.27 1.27)
				)
				(justify left bottom)
			)
		)
		(property "Value" "TP_0.75mm_SMD"
			(at 104.14 128.27 0)
			(effects
				(font
					(size 1.27 1.27)
					(thickness 0.15)
				)
				(justify left bottom)
				(hide yes)
			)
		)
		(property "Footprint" "antmicro-footprints:TP_SMD_0.75mm"
			(at 104.14 125.73 0)
			(effects
				(font
					(size 1.27 1.27)
					(thickness 0.15)
				)
				(justify left bottom)
				(hide yes)
			)
		)
		(property "Datasheet" ""
			(at 96.52 119.38 0)
			(effects
				(font
					(size 1.27 1.27)
					(thickness 0.15)
				)
				(justify left bottom)
				(hide yes)
			)
		)
		(property "Description" "SMT test point"
			(at 114.3 132.08 0)
			(effects
				(font
					(size 1.27 1.27)
				)
				(hide yes)
			)
		)
		(property "MPN" ""
			(at 103.505 120.65 0)
			(effects
				(font
					(size 1.27 1.27)
					(thickness 0.15)
				)
				(justify left bottom)
				(hide yes)
			)
		)
		(property "Manufacturer" ""
			(at 103.505 125.73 0)
			(effects
				(font
					(size 1.27 1.27)
					(thickness 0.15)
				)
				(justify left bottom)
				(hide yes)
			)
		)
		(property "Author" "Antmicro"
			(at 104.14 123.19 0)
			(effects
				(font
					(size 1.27 1.27)
					(thickness 0.15)
				)
				(justify left bottom)
				(hide yes)
			)
		)
		(property "License" "Apache-2.0"
			(at 104.14 120.65 0)
			(effects
				(font
					(size 1.27 1.27)
					(thickness 0.15)
				)
				(justify left bottom)
				(hide yes)
			)
		)
		(pin "1"
		)
		(instances
			(project "jetson-agx-thor-baseboard"
				(path ""
					(reference "TP1")
					(unit 1)
				)
			)
		)
	)
	(symbol
		(lib_id "antmicroCapacitors0402:C_100n_0402")
		(at 78.74 48.26 90)
		(unit 1)
		(exclude_from_sim no)
		(in_bom yes)
		(on_board yes)
		(dnp no)
		(fields_autoplaced yes)
		(property "Reference" "C95"
			(at 81.28 44.4436 90)
			(effects
				(font
					(size 1.27 1.27)
					(thickness 0.15)
				)
				(justify right)
			)
		)
		(property "Value" "C_100n_0402"
			(at 101.6 33.02 0)
			(effects
				(font
					(size 1.27 1.27)
					(thickness 0.15)
				)
				(justify left bottom)
				(hide yes)
			)
		)
		(property "Footprint" "antmicro-footprints:C_0402_1005Metric"
			(at 104.14 33.02 0)
			(effects
				(font
					(size 1.27 1.27)
					(thickness 0.15)
				)
				(justify left bottom)
				(hide yes)
			)
		)
		(property "Datasheet" "https://www.murata.com/products/productdetail?partno=GRM155R61H104KE14%23"
			(at 106.68 33.02 0)
			(effects
				(font
					(size 1.27 1.27)
					(thickness 0.15)
				)
				(justify left bottom)
				(hide yes)
			)
		)
		(property "Description" "SMD Multilayer Ceramic Capacitor, 0.1 µF, 50 V, 0402 [1005 Metric], ± 10%, X5R, GRM Series"
			(at 78.74 48.26 0)
			(effects
				(font
					(size 1.27 1.27)
				)
				(hide yes)
			)
		)
		(property "MPN" "GRM155R61H104KE14D"
			(at 109.22 33.02 0)
			(effects
				(font
					(size 1.27 1.27)
					(thickness 0.15)
				)
				(justify left bottom)
				(hide yes)
			)
		)
		(property "Val" "100n"
			(at 81.28 46.9836 90)
			(effects
				(font
					(size 1.27 1.27)
					(thickness 0.15)
				)
				(justify right)
			)
		)
		(property "Voltage" "50V"
			(at 88.9 33.02 0)
			(effects
				(font
					(size 1.27 1.27)
					(thickness 0.15)
				)
				(justify left bottom)
				(hide yes)
			)
		)
		(property "Dielectric" "X5R"
			(at 91.44 33.02 0)
			(effects
				(font
					(size 1.27 1.27)
					(thickness 0.15)
				)
				(justify left bottom)
				(hide yes)
			)
		)
		(property "Manufacturer" "Murata"
			(at 93.98 33.02 0)
			(effects
				(font
					(size 1.27 1.27)
					(thickness 0.15)
				)
				(justify left bottom)
				(hide yes)
			)
		)
		(property "License" "Apache-2.0"
			(at 96.52 33.02 0)
			(effects
				(font
					(size 1.27 1.27)
					(thickness 0.15)
				)
				(justify left bottom)
				(hide yes)
			)
		)
		(property "Author" "Antmicro"
			(at 99.06 33.02 0)
			(effects
				(font
					(size 1.27 1.27)
					(thickness 0.15)
				)
				(justify left bottom)
				(hide yes)
			)
		)
		(pin "1"
		)
		(pin "2"
		)
		(instances
			(project "jetson-agx-thor-baseboard"
				(path ""
					(reference "C95")
					(unit 1)
				)
			)
		)
	)
	(symbol
		(lib_id "antmicropower:+3V3")
		(at 71.12 148.59 0)
		(unit 1)
		(exclude_from_sim no)
		(in_bom yes)
		(on_board yes)
		(dnp no)
		(fields_autoplaced yes)
		(property "Reference" "#PWR0187"
			(at 86.36 148.59 0)
			(effects
				(font
					(size 1.27 1.27)
					(thickness 0.15)
				)
				(justify left bottom)
				(hide yes)
			)
		)
		(property "Value" "+3V3"
			(at 71.12 143.51 0)
			(effects
				(font
					(size 1.27 1.27)
					(thickness 0.15)
				)
			)
		)
		(property "Footprint" ""
			(at 86.36 156.21 0)
			(effects
				(font
					(size 1.27 1.27)
					(thickness 0.15)
				)
				(justify left bottom)
				(hide yes)
			)
		)
		(property "Datasheet" ""
			(at 86.36 158.75 0)
			(effects
				(font
					(size 1.27 1.27)
					(thickness 0.15)
				)
				(justify left bottom)
				(hide yes)
			)
		)
		(property "Description" ""
			(at 71.12 148.59 0)
			(effects
				(font
					(size 1.27 1.27)
				)
				(hide yes)
			)
		)
		(property "Author" "Antmicro"
			(at 86.36 151.13 0)
			(effects
				(font
					(size 1.27 1.27)
					(thickness 0.15)
				)
				(justify left bottom)
				(hide yes)
			)
		)
		(property "License" "Apache-2.0"
			(at 86.36 153.67 0)
			(effects
				(font
					(size 1.27 1.27)
					(thickness 0.15)
				)
				(justify left bottom)
				(hide yes)
			)
		)
		(pin "1"
		)
		(instances
			(project "jetson-agx-thor-baseboard"
				(path ""
					(reference "#PWR0187")
					(unit 1)
				)
			)
		)
	)
	(symbol
		(lib_id "antmicroResistors0402:R_470R_0402")
		(at 392.43 160.02 90)
		(unit 1)
		(exclude_from_sim no)
		(in_bom yes)
		(on_board yes)
		(dnp no)
		(property "Reference" "R260"
			(at 393.7 156.21 90)
			(effects
				(font
					(size 1.27 1.27)
				)
				(justify right)
			)
		)
		(property "Value" "R_470R_0402"
			(at 405.13 139.7 0)
			(effects
				(font
					(size 1.27 1.27)
					(thickness 0.15)
				)
				(justify left bottom)
				(hide yes)
			)
		)
		(property "Footprint" "antmicro-footprints:R_0402_1005Metric"
			(at 407.67 139.7 0)
			(effects
				(font
					(size 1.27 1.27)
					(thickness 0.15)
				)
				(justify left bottom)
				(hide yes)
			)
		)
		(property "Datasheet" "https://www.bourns.com/docs/product-datasheets/cr.pdf"
			(at 410.21 139.7 0)
			(effects
				(font
					(size 1.27 1.27)
					(thickness 0.15)
				)
				(justify left bottom)
				(hide yes)
			)
		)
		(property "Description" "SMD Chip Resistor, 470 ohm, ± 1%, 62.5 mW, 0402 [1005 Metric], Thick Film, General Purpose"
			(at 392.43 160.02 0)
			(effects
				(font
					(size 1.27 1.27)
				)
				(hide yes)
			)
		)
		(property "Manufacturer" "Bourns"
			(at 415.29 139.7 0)
			(effects
				(font
					(size 1.27 1.27)
					(thickness 0.15)
				)
				(justify left bottom)
				(hide yes)
			)
		)
		(property "MPN" "CR0402-FX-4700GLF"
			(at 412.75 139.7 0)
			(effects
				(font
					(size 1.27 1.27)
					(thickness 0.15)
				)
				(justify left bottom)
				(hide yes)
			)
		)
		(property "Val" "470R"
			(at 393.7 158.75 90)
			(effects
				(font
					(size 1.27 1.27)
					(thickness 0.15)
				)
				(justify right)
			)
		)
		(property "License" "Apache-2.0"
			(at 417.83 139.7 0)
			(effects
				(font
					(size 1.27 1.27)
					(thickness 0.15)
				)
				(justify left bottom)
				(hide yes)
			)
		)
		(property "Author" "Antmicro"
			(at 420.37 139.7 0)
			(effects
				(font
					(size 1.27 1.27)
					(thickness 0.15)
				)
				(justify left bottom)
				(hide yes)
			)
		)
		(property "Tolerance" "1%"
			(at 402.59 139.7 0)
			(effects
				(font
					(size 1.27 1.27)
				)
				(justify left bottom)
				(hide yes)
			)
		)
		(pin "1"
		)
		(pin "2"
		)
		(instances
			(project "jetson-agx-thor-baseboard"
				(path ""
					(reference "R260")
					(unit 1)
				)
			)
		)
	)
	(symbol
		(lib_id "antmicroCapacitors0402:C_100n_0402")
		(at 78.74 66.04 90)
		(unit 1)
		(exclude_from_sim no)
		(in_bom yes)
		(on_board yes)
		(dnp no)
		(fields_autoplaced yes)
		(property "Reference" "C91"
			(at 81.28 62.2236 90)
			(effects
				(font
					(size 1.27 1.27)
					(thickness 0.15)
				)
				(justify right)
			)
		)
		(property "Value" "C_100n_0402"
			(at 101.6 50.8 0)
			(effects
				(font
					(size 1.27 1.27)
					(thickness 0.15)
				)
				(justify left bottom)
				(hide yes)
			)
		)
		(property "Footprint" "antmicro-footprints:C_0402_1005Metric"
			(at 104.14 50.8 0)
			(effects
				(font
					(size 1.27 1.27)
					(thickness 0.15)
				)
				(justify left bottom)
				(hide yes)
			)
		)
		(property "Datasheet" "https://www.murata.com/products/productdetail?partno=GRM155R61H104KE14%23"
			(at 106.68 50.8 0)
			(effects
				(font
					(size 1.27 1.27)
					(thickness 0.15)
				)
				(justify left bottom)
				(hide yes)
			)
		)
		(property "Description" "SMD Multilayer Ceramic Capacitor, 0.1 µF, 50 V, 0402 [1005 Metric], ± 10%, X5R, GRM Series"
			(at 78.74 66.04 0)
			(effects
				(font
					(size 1.27 1.27)
				)
				(hide yes)
			)
		)
		(property "MPN" "GRM155R61H104KE14D"
			(at 109.22 50.8 0)
			(effects
				(font
					(size 1.27 1.27)
					(thickness 0.15)
				)
				(justify left bottom)
				(hide yes)
			)
		)
		(property "Val" "100n"
			(at 81.28 64.7636 90)
			(effects
				(font
					(size 1.27 1.27)
					(thickness 0.15)
				)
				(justify right)
			)
		)
		(property "Voltage" "50V"
			(at 88.9 50.8 0)
			(effects
				(font
					(size 1.27 1.27)
					(thickness 0.15)
				)
				(justify left bottom)
				(hide yes)
			)
		)
		(property "Dielectric" "X5R"
			(at 91.44 50.8 0)
			(effects
				(font
					(size 1.27 1.27)
					(thickness 0.15)
				)
				(justify left bottom)
				(hide yes)
			)
		)
		(property "Manufacturer" "Murata"
			(at 93.98 50.8 0)
			(effects
				(font
					(size 1.27 1.27)
					(thickness 0.15)
				)
				(justify left bottom)
				(hide yes)
			)
		)
		(property "License" "Apache-2.0"
			(at 96.52 50.8 0)
			(effects
				(font
					(size 1.27 1.27)
					(thickness 0.15)
				)
				(justify left bottom)
				(hide yes)
			)
		)
		(property "Author" "Antmicro"
			(at 99.06 50.8 0)
			(effects
				(font
					(size 1.27 1.27)
					(thickness 0.15)
				)
				(justify left bottom)
				(hide yes)
			)
		)
		(pin "1"
		)
		(pin "2"
		)
		(instances
			(project "jetson-agx-thor-baseboard"
				(path ""
					(reference "C91")
					(unit 1)
				)
			)
		)
	)
	(symbol
		(lib_id "antmicroTestPoints:TP_0.75mm_SMD")
		(at 370.84 29.21 90)
		(unit 1)
		(exclude_from_sim no)
		(in_bom no)
		(on_board yes)
		(dnp no)
		(property "Reference" "TP43"
			(at 370.84 25.4 0)
			(effects
				(font
					(size 1.27 1.27)
				)
				(justify left)
			)
		)
		(property "Value" "TP_0.75mm_SMD"
			(at 374.65 19.05 0)
			(effects
				(font
					(size 1.27 1.27)
					(thickness 0.15)
				)
				(justify left bottom)
				(hide yes)
			)
		)
		(property "Footprint" "antmicro-footprints:TP_SMD_0.75mm"
			(at 377.19 19.05 0)
			(effects
				(font
					(size 1.27 1.27)
					(thickness 0.15)
				)
				(justify left bottom)
				(hide yes)
			)
		)
		(property "Datasheet" ""
			(at 383.54 11.43 0)
			(effects
				(font
					(size 1.27 1.27)
					(thickness 0.15)
				)
				(justify left bottom)
				(hide yes)
			)
		)
		(property "Description" "SMT test point"
			(at 370.84 29.21 0)
			(effects
				(font
					(size 1.27 1.27)
				)
				(hide yes)
			)
		)
		(property "MPN" ""
			(at 382.27 18.415 0)
			(effects
				(font
					(size 1.27 1.27)
					(thickness 0.15)
				)
				(justify left bottom)
				(hide yes)
			)
		)
		(property "Manufacturer" ""
			(at 377.19 18.415 0)
			(effects
				(font
					(size 1.27 1.27)
					(thickness 0.15)
				)
				(justify left bottom)
				(hide yes)
			)
		)
		(property "Author" "Antmicro"
			(at 379.73 19.05 0)
			(effects
				(font
					(size 1.27 1.27)
					(thickness 0.15)
				)
				(justify left bottom)
				(hide yes)
			)
		)
		(property "License" "Apache-2.0"
			(at 382.27 19.05 0)
			(effects
				(font
					(size 1.27 1.27)
					(thickness 0.15)
				)
				(justify left bottom)
				(hide yes)
			)
		)
		(pin "1"
		)
		(instances
			(project "jetson-agx-thor-baseboard"
				(path ""
					(reference "TP43")
					(unit 1)
				)
			)
		)
	)
	(symbol
		(lib_id "antmicroCapacitorsmisc:C_22u_25V_0805")
		(at 351.79 33.02 90)
		(mirror x)
		(unit 1)
		(exclude_from_sim no)
		(in_bom yes)
		(on_board yes)
		(dnp no)
		(fields_autoplaced yes)
		(property "Reference" "C78"
			(at 354.33 34.2963 90)
			(effects
				(font
					(size 1.27 1.27)
				)
				(justify right)
			)
		)
		(property "Value" "C_22u_25V_0805"
			(at 361.95 53.34 0)
			(effects
				(font
					(size 1.27 1.27)
					(thickness 0.15)
				)
				(justify left bottom)
				(hide yes)
			)
		)
		(property "Footprint" "antmicro-footprints:C_0805_2012Metric"
			(at 364.49 53.34 0)
			(effects
				(font
					(size 1.27 1.27)
					(thickness 0.15)
				)
				(justify left bottom)
				(hide yes)
			)
		)
		(property "Datasheet" "https://product.samsungsem.com/mlcc/CL21A226MAYNNN.do"
			(at 367.03 53.34 0)
			(effects
				(font
					(size 1.27 1.27)
					(thickness 0.15)
				)
				(justify left bottom)
				(hide yes)
			)
		)
		(property "Description" "SMT Multilayer Ceramic Capacitor, 22uF, +/-20%, 25V, X5R, 0805 [2012 Metric]"
			(at 351.79 33.02 0)
			(effects
				(font
					(size 1.27 1.27)
				)
				(hide yes)
			)
		)
		(property "Manufacturer" "Samsung Electro-Mechanics"
			(at 372.11 53.34 0)
			(effects
				(font
					(size 1.27 1.27)
					(thickness 0.15)
				)
				(justify left bottom)
				(hide yes)
			)
		)
		(property "MPN" "CL21A226MAYNNNE"
			(at 369.57 53.34 0)
			(effects
				(font
					(size 1.27 1.27)
					(thickness 0.15)
				)
				(justify left bottom)
				(hide yes)
			)
		)
		(property "Val" "22u"
			(at 354.33 36.8363 90)
			(effects
				(font
					(size 1.27 1.27)
					(thickness 0.15)
				)
				(justify right)
			)
		)
		(property "License" "Apache-2.0"
			(at 374.65 53.34 0)
			(effects
				(font
					(size 1.27 1.27)
					(thickness 0.15)
				)
				(justify left bottom)
				(hide yes)
			)
		)
		(property "Author" "Antmicro"
			(at 377.19 53.34 0)
			(effects
				(font
					(size 1.27 1.27)
					(thickness 0.15)
				)
				(justify left bottom)
				(hide yes)
			)
		)
		(property "Voltage" "25V"
			(at 379.73 53.34 0)
			(effects
				(font
					(size 1.27 1.27)
				)
				(justify left bottom)
				(hide yes)
			)
		)
		(property "Dielectric" "X5R"
			(at 382.27 53.34 0)
			(effects
				(font
					(size 1.27 1.27)
				)
				(justify left bottom)
				(hide yes)
			)
		)
		(property "Public" "False"
			(at 384.81 53.34 0)
			(effects
				(font
					(size 1.27 1.27)
				)
				(justify left bottom)
				(hide yes)
			)
		)
		(pin "1"
		)
		(pin "2"
		)
		(instances
			(project "jetson-agx-thor-baseboard"
				(path ""
					(reference "C78")
					(unit 1)
				)
			)
		)
	)
	(symbol
		(lib_id "antmicropower:GND")
		(at 43.18 198.12 0)
		(mirror y)
		(unit 1)
		(exclude_from_sim no)
		(in_bom yes)
		(on_board yes)
		(dnp no)
		(property "Reference" "#PWR0199"
			(at 43.18 204.47 0)
			(effects
				(font
					(size 1.27 1.27)
				)
				(justify left bottom)
				(hide yes)
			)
		)
		(property "Value" "GND"
			(at 43.18 201.93 0)
			(effects
				(font
					(size 1.27 1.27)
					(thickness 0.15)
				)
			)
		)
		(property "Footprint" ""
			(at 34.29 205.74 0)
			(effects
				(font
					(size 1.27 1.27)
					(thickness 0.15)
				)
				(justify left bottom)
				(hide yes)
			)
		)
		(property "Datasheet" ""
			(at 34.29 210.82 0)
			(effects
				(font
					(size 1.27 1.27)
					(thickness 0.15)
				)
				(justify left bottom)
				(hide yes)
			)
		)
		(property "Description" ""
			(at 43.18 198.12 0)
			(effects
				(font
					(size 1.27 1.27)
				)
				(hide yes)
			)
		)
		(property "Author" "Antmicro"
			(at 34.29 205.74 0)
			(effects
				(font
					(size 1.27 1.27)
					(thickness 0.15)
				)
				(justify left bottom)
				(hide yes)
			)
		)
		(property "License" "Apache-2.0"
			(at 34.29 208.28 0)
			(effects
				(font
					(size 1.27 1.27)
					(thickness 0.15)
				)
				(justify left bottom)
				(hide yes)
			)
		)
		(pin "1"
		)
		(instances
			(project "jetson-agx-thor-baseboard"
				(path ""
					(reference "#PWR0199")
					(unit 1)
				)
			)
		)
	)
	(symbol
		(lib_id "antmicroCapacitors0402:C_100n_0402")
		(at 285.75 210.82 180)
		(unit 1)
		(exclude_from_sim no)
		(in_bom yes)
		(on_board yes)
		(dnp no)
		(property "Reference" "C81"
			(at 289.56 208.788 0)
			(effects
				(font
					(size 1.27 1.27)
				)
				(justify left bottom)
			)
		)
		(property "Value" "C_100n_0402"
			(at 265.43 200.66 0)
			(effects
				(font
					(size 1.27 1.27)
					(thickness 0.15)
				)
				(justify left bottom)
				(hide yes)
			)
		)
		(property "Footprint" "antmicro-footprints:C_0402_1005Metric"
			(at 265.43 198.12 0)
			(effects
				(font
					(size 1.27 1.27)
					(thickness 0.15)
				)
				(justify left bottom)
				(hide yes)
			)
		)
		(property "Datasheet" "https://www.murata.com/products/productdetail?partno=GRM155R61H104KE14%23"
			(at 265.43 195.58 0)
			(effects
				(font
					(size 1.27 1.27)
					(thickness 0.15)
				)
				(justify left bottom)
				(hide yes)
			)
		)
		(property "Description" "SMD Multilayer Ceramic Capacitor, 0.1 µF, 50 V, 0402 [1005 Metric], ± 10%, X5R, GRM Series"
			(at 285.75 210.82 0)
			(effects
				(font
					(size 1.27 1.27)
				)
				(hide yes)
			)
		)
		(property "Manufacturer" "Murata"
			(at 265.43 190.5 0)
			(effects
				(font
					(size 1.27 1.27)
					(thickness 0.15)
				)
				(justify left bottom)
				(hide yes)
			)
		)
		(property "MPN" "GRM155R61H104KE14D"
			(at 265.43 193.04 0)
			(effects
				(font
					(size 1.27 1.27)
					(thickness 0.15)
				)
				(justify left bottom)
				(hide yes)
			)
		)
		(property "Val" "100n"
			(at 281.94 211.455 0)
			(effects
				(font
					(size 1.27 1.27)
					(thickness 0.15)
				)
				(justify left bottom)
			)
		)
		(property "License" "Apache-2.0"
			(at 265.43 187.96 0)
			(effects
				(font
					(size 1.27 1.27)
					(thickness 0.15)
				)
				(justify left bottom)
				(hide yes)
			)
		)
		(property "Author" "Antmicro"
			(at 265.43 185.42 0)
			(effects
				(font
					(size 1.27 1.27)
					(thickness 0.15)
				)
				(justify left bottom)
				(hide yes)
			)
		)
		(property "Voltage" "50V"
			(at 265.43 182.88 0)
			(effects
				(font
					(size 1.27 1.27)
				)
				(justify left bottom)
				(hide yes)
			)
		)
		(property "Dielectric" "X5R"
			(at 265.43 180.34 0)
			(effects
				(font
					(size 1.27 1.27)
				)
				(justify left bottom)
				(hide yes)
			)
		)
		(pin "1"
		)
		(pin "2"
		)
		(instances
			(project "jetson-agx-thor-baseboard"
				(path ""
					(reference "C81")
					(unit 1)
				)
			)
		)
	)
	(symbol
		(lib_id "antmicroOscillators:Oscillator_25MHz_ESC_2016MV")
		(at 82.55 148.59 0)
		(unit 1)
		(exclude_from_sim no)
		(in_bom yes)
		(on_board yes)
		(dnp no)
		(property "Reference" "Y2"
			(at 90.678 144.526 0)
			(effects
				(font
					(size 1.27 1.27)
					(thickness 0.15)
				)
			)
		)
		(property "Value" "Oscillator_25MHz_ESC_2016MV"
			(at 107.95 161.29 0)
			(effects
				(font
					(size 1.27 1.27)
					(thickness 0.15)
				)
				(justify left bottom)
				(hide yes)
			)
		)
		(property "Footprint" "antmicro-footprints:Oscillator_SMD_ECS_2016MV_2x1.6x0.85mm"
			(at 107.95 163.83 0)
			(effects
				(font
					(size 1.27 1.27)
					(thickness 0.15)
				)
				(justify left bottom)
				(hide yes)
			)
		)
		(property "Datasheet" "https://ecsxtal.com/store/pdf/ECS-2016MV.pdf"
			(at 107.95 166.37 0)
			(effects
				(font
					(size 1.27 1.27)
					(thickness 0.15)
				)
				(justify left bottom)
				(hide yes)
			)
		)
		(property "Description" "Oscillator, 25 MHz, HCMOS, SMD, 2mm x 1.6mm, MultiVolt ECS-2016MV Series"
			(at 82.55 148.59 0)
			(effects
				(font
					(size 1.27 1.27)
				)
				(hide yes)
			)
		)
		(property "MPN" "ECS-2016MV-250-CN-TR"
			(at 106.172 143.51 0)
			(effects
				(font
					(size 1.27 1.27)
					(thickness 0.15)
				)
			)
		)
		(property "Manufacturer" "ECS Inc. International"
			(at 107.95 156.21 0)
			(effects
				(font
					(size 1.27 1.27)
					(thickness 0.15)
				)
				(justify left bottom)
				(hide yes)
			)
		)
		(property "Val" "25 MHz"
			(at 106.172 146.05 0)
			(effects
				(font
					(size 1.27 1.27)
					(thickness 0.15)
				)
			)
		)
		(property "Author" "Antmicro"
			(at 107.95 168.91 0)
			(effects
				(font
					(size 1.27 1.27)
					(thickness 0.15)
				)
				(justify left bottom)
				(hide yes)
			)
		)
		(property "License" "Apache-2.0"
			(at 107.95 171.45 0)
			(effects
				(font
					(size 1.27 1.27)
					(thickness 0.15)
				)
				(justify left bottom)
				(hide yes)
			)
		)
		(pin "3"
		)
		(pin "4"
		)
		(pin "1"
		)
		(pin "2"
		)
		(instances
			(project "jetson-agx-thor-baseboard"
				(path ""
					(reference "Y2")
					(unit 1)
				)
			)
		)
	)
	(symbol
		(lib_id "antmicropower:GND")
		(at 74.93 234.95 0)
		(mirror y)
		(unit 1)
		(exclude_from_sim no)
		(in_bom yes)
		(on_board yes)
		(dnp no)
		(property "Reference" "#PWR0203"
			(at 74.93 241.3 0)
			(effects
				(font
					(size 1.27 1.27)
				)
				(justify left bottom)
				(hide yes)
			)
		)
		(property "Value" "GND"
			(at 74.93 238.76 0)
			(effects
				(font
					(size 1.27 1.27)
					(thickness 0.15)
				)
			)
		)
		(property "Footprint" ""
			(at 66.04 242.57 0)
			(effects
				(font
					(size 1.27 1.27)
					(thickness 0.15)
				)
				(justify left bottom)
				(hide yes)
			)
		)
		(property "Datasheet" ""
			(at 66.04 247.65 0)
			(effects
				(font
					(size 1.27 1.27)
					(thickness 0.15)
				)
				(justify left bottom)
				(hide yes)
			)
		)
		(property "Description" ""
			(at 74.93 234.95 0)
			(effects
				(font
					(size 1.27 1.27)
				)
				(hide yes)
			)
		)
		(property "Author" "Antmicro"
			(at 66.04 242.57 0)
			(effects
				(font
					(size 1.27 1.27)
					(thickness 0.15)
				)
				(justify left bottom)
				(hide yes)
			)
		)
		(property "License" "Apache-2.0"
			(at 66.04 245.11 0)
			(effects
				(font
					(size 1.27 1.27)
					(thickness 0.15)
				)
				(justify left bottom)
				(hide yes)
			)
		)
		(pin "1"
		)
		(instances
			(project "jetson-agx-thor-baseboard"
				(path ""
					(reference "#PWR0203")
					(unit 1)
				)
			)
		)
	)
	(symbol
		(lib_id "antmicropower:GND")
		(at 392.43 167.64 0)
		(unit 1)
		(exclude_from_sim no)
		(in_bom yes)
		(on_board yes)
		(dnp no)
		(property "Reference" "#PWR0468"
			(at 392.43 173.99 0)
			(effects
				(font
					(size 1.27 1.27)
				)
				(justify left bottom)
				(hide yes)
			)
		)
		(property "Value" "GND"
			(at 392.43 171.45 0)
			(effects
				(font
					(size 1.27 1.27)
					(thickness 0.15)
				)
			)
		)
		(property "Footprint" ""
			(at 401.32 175.26 0)
			(effects
				(font
					(size 1.27 1.27)
					(thickness 0.15)
				)
				(justify left bottom)
				(hide yes)
			)
		)
		(property "Datasheet" ""
			(at 401.32 180.34 0)
			(effects
				(font
					(size 1.27 1.27)
					(thickness 0.15)
				)
				(justify left bottom)
				(hide yes)
			)
		)
		(property "Description" ""
			(at 392.43 167.64 0)
			(effects
				(font
					(size 1.27 1.27)
				)
				(hide yes)
			)
		)
		(property "Author" "Antmicro"
			(at 401.32 175.26 0)
			(effects
				(font
					(size 1.27 1.27)
					(thickness 0.15)
				)
				(justify left bottom)
				(hide yes)
			)
		)
		(property "License" "Apache-2.0"
			(at 401.32 177.8 0)
			(effects
				(font
					(size 1.27 1.27)
					(thickness 0.15)
				)
				(justify left bottom)
				(hide yes)
			)
		)
		(pin "1"
		)
		(instances
			(project "jetson-agx-thor-baseboard"
				(path ""
					(reference "#PWR0468")
					(unit 1)
				)
			)
		)
	)
	(symbol
		(lib_id "antmicroDiodesRectifiersSingle:RB521S30T1G")
		(at 71.12 226.06 180)
		(unit 1)
		(exclude_from_sim no)
		(in_bom yes)
		(on_board yes)
		(dnp no)
		(property "Reference" "D15"
			(at 71.882 219.71 0)
			(effects
				(font
					(size 1.27 1.27)
				)
			)
		)
		(property "Value" "RB521S30T1G"
			(at 48.26 210.82 0)
			(effects
				(font
					(size 1.27 1.27)
					(thickness 0.15)
				)
				(justify left bottom)
				(hide yes)
			)
		)
		(property "Footprint" "antmicro-footprints:SOD-523"
			(at 48.26 215.9 0)
			(effects
				(font
					(size 1.27 1.27)
					(thickness 0.15)
				)
				(justify left bottom)
				(hide yes)
			)
		)
		(property "Datasheet" "https://www.onsemi.com/pdf/datasheet/rb521s30t1-d.pdf"
			(at 48.26 213.36 0)
			(effects
				(font
					(size 1.27 1.27)
					(thickness 0.15)
				)
				(justify left bottom)
				(hide yes)
			)
		)
		(property "Description" "Small Signal Schottky Diode, Single, 30 V, 200 mA, 500 mV, 1 A, 125 °C"
			(at 71.12 226.06 0)
			(effects
				(font
					(size 1.27 1.27)
				)
				(hide yes)
			)
		)
		(property "MPN" "RB521S30T1G"
			(at 71.882 222.25 0)
			(effects
				(font
					(size 1.27 1.27)
					(thickness 0.15)
				)
			)
		)
		(property "Manufacturer" "ON Semiconductor"
			(at 48.26 208.28 0)
			(effects
				(font
					(size 1.27 1.27)
					(thickness 0.15)
				)
				(justify left bottom)
				(hide yes)
			)
		)
		(property "Author" "Antmicro"
			(at 48.26 205.74 0)
			(effects
				(font
					(size 1.27 1.27)
					(thickness 0.15)
				)
				(justify left bottom)
				(hide yes)
			)
		)
		(property "License" "Apache-2.0"
			(at 48.26 203.2 0)
			(effects
				(font
					(size 1.27 1.27)
					(thickness 0.15)
				)
				(justify left bottom)
				(hide yes)
			)
		)
		(pin "1"
		)
		(pin "2"
		)
		(instances
			(project "jetson-agx-thor-baseboard"
				(path ""
					(reference "D15")
					(unit 1)
				)
			)
		)
	)
	(symbol
		(lib_id "antmicropower:GND")
		(at 308.61 27.94 0)
		(unit 1)
		(exclude_from_sim no)
		(in_bom yes)
		(on_board yes)
		(dnp no)
		(property "Reference" "#PWR0171"
			(at 308.61 34.29 0)
			(effects
				(font
					(size 1.27 1.27)
				)
				(justify left bottom)
				(hide yes)
			)
		)
		(property "Value" "GND"
			(at 308.61 31.75 0)
			(effects
				(font
					(size 1.27 1.27)
					(thickness 0.15)
				)
			)
		)
		(property "Footprint" ""
			(at 317.5 35.56 0)
			(effects
				(font
					(size 1.27 1.27)
					(thickness 0.15)
				)
				(justify left bottom)
				(hide yes)
			)
		)
		(property "Datasheet" ""
			(at 317.5 40.64 0)
			(effects
				(font
					(size 1.27 1.27)
					(thickness 0.15)
				)
				(justify left bottom)
				(hide yes)
			)
		)
		(property "Description" ""
			(at 308.61 27.94 0)
			(effects
				(font
					(size 1.27 1.27)
				)
				(hide yes)
			)
		)
		(property "Author" "Antmicro"
			(at 317.5 35.56 0)
			(effects
				(font
					(size 1.27 1.27)
					(thickness 0.15)
				)
				(justify left bottom)
				(hide yes)
			)
		)
		(property "License" "Apache-2.0"
			(at 317.5 38.1 0)
			(effects
				(font
					(size 1.27 1.27)
					(thickness 0.15)
				)
				(justify left bottom)
				(hide yes)
			)
		)
		(pin "1"
		)
		(instances
			(project "jetson-agx-thor-baseboard"
				(path ""
					(reference "#PWR0171")
					(unit 1)
				)
			)
		)
	)
	(symbol
		(lib_id "antmicropower:GND")
		(at 167.64 266.7 0)
		(mirror y)
		(unit 1)
		(exclude_from_sim no)
		(in_bom yes)
		(on_board yes)
		(dnp no)
		(property "Reference" "#PWR0672"
			(at 167.64 273.05 0)
			(effects
				(font
					(size 1.27 1.27)
				)
				(justify left bottom)
				(hide yes)
			)
		)
		(property "Value" "GND"
			(at 167.64 270.51 0)
			(effects
				(font
					(size 1.27 1.27)
					(thickness 0.15)
				)
			)
		)
		(property "Footprint" ""
			(at 158.75 274.32 0)
			(effects
				(font
					(size 1.27 1.27)
					(thickness 0.15)
				)
				(justify left bottom)
				(hide yes)
			)
		)
		(property "Datasheet" ""
			(at 158.75 279.4 0)
			(effects
				(font
					(size 1.27 1.27)
					(thickness 0.15)
				)
				(justify left bottom)
				(hide yes)
			)
		)
		(property "Description" ""
			(at 167.64 266.7 0)
			(effects
				(font
					(size 1.27 1.27)
				)
				(hide yes)
			)
		)
		(property "Author" "Antmicro"
			(at 158.75 274.32 0)
			(effects
				(font
					(size 1.27 1.27)
					(thickness 0.15)
				)
				(justify left bottom)
				(hide yes)
			)
		)
		(property "License" "Apache-2.0"
			(at 158.75 276.86 0)
			(effects
				(font
					(size 1.27 1.27)
					(thickness 0.15)
				)
				(justify left bottom)
				(hide yes)
			)
		)
		(pin "1"
		)
		(instances
			(project "jetson-agx-thor-baseboard"
				(path ""
					(reference "#PWR0672")
					(unit 1)
				)
			)
		)
	)
	(symbol
		(lib_id "antmicroCapacitors0402:C_100n_0402")
		(at 289.56 213.36 180)
		(unit 1)
		(exclude_from_sim no)
		(in_bom yes)
		(on_board yes)
		(dnp no)
		(property "Reference" "C83"
			(at 293.37 211.328 0)
			(effects
				(font
					(size 1.27 1.27)
				)
				(justify left bottom)
			)
		)
		(property "Value" "C_100n_0402"
			(at 269.24 203.2 0)
			(effects
				(font
					(size 1.27 1.27)
					(thickness 0.15)
				)
				(justify left bottom)
				(hide yes)
			)
		)
		(property "Footprint" "antmicro-footprints:C_0402_1005Metric"
			(at 269.24 200.66 0)
			(effects
				(font
					(size 1.27 1.27)
					(thickness 0.15)
				)
				(justify left bottom)
				(hide yes)
			)
		)
		(property "Datasheet" "https://www.murata.com/products/productdetail?partno=GRM155R61H104KE14%23"
			(at 269.24 198.12 0)
			(effects
				(font
					(size 1.27 1.27)
					(thickness 0.15)
				)
				(justify left bottom)
				(hide yes)
			)
		)
		(property "Description" "SMD Multilayer Ceramic Capacitor, 0.1 µF, 50 V, 0402 [1005 Metric], ± 10%, X5R, GRM Series"
			(at 289.56 213.36 0)
			(effects
				(font
					(size 1.27 1.27)
				)
				(hide yes)
			)
		)
		(property "Manufacturer" "Murata"
			(at 269.24 193.04 0)
			(effects
				(font
					(size 1.27 1.27)
					(thickness 0.15)
				)
				(justify left bottom)
				(hide yes)
			)
		)
		(property "MPN" "GRM155R61H104KE14D"
			(at 269.24 195.58 0)
			(effects
				(font
					(size 1.27 1.27)
					(thickness 0.15)
				)
				(justify left bottom)
				(hide yes)
			)
		)
		(property "Val" "100n"
			(at 285.75 213.995 0)
			(effects
				(font
					(size 1.27 1.27)
					(thickness 0.15)
				)
				(justify left bottom)
			)
		)
		(property "License" "Apache-2.0"
			(at 269.24 190.5 0)
			(effects
				(font
					(size 1.27 1.27)
					(thickness 0.15)
				)
				(justify left bottom)
				(hide yes)
			)
		)
		(property "Author" "Antmicro"
			(at 269.24 187.96 0)
			(effects
				(font
					(size 1.27 1.27)
					(thickness 0.15)
				)
				(justify left bottom)
				(hide yes)
			)
		)
		(property "Voltage" "50V"
			(at 269.24 185.42 0)
			(effects
				(font
					(size 1.27 1.27)
				)
				(justify left bottom)
				(hide yes)
			)
		)
		(property "Dielectric" "X5R"
			(at 269.24 182.88 0)
			(effects
				(font
					(size 1.27 1.27)
				)
				(justify left bottom)
				(hide yes)
			)
		)
		(pin "1"
		)
		(pin "2"
		)
		(instances
			(project "jetson-agx-thor-baseboard"
				(path ""
					(reference "C83")
					(unit 1)
				)
			)
		)
	)
	(symbol
		(lib_id "antmicroResistors0402:R_0R_0402")
		(at 52.07 243.84 0)
		(unit 1)
		(exclude_from_sim no)
		(in_bom no)
		(on_board yes)
		(dnp yes)
		(fields_autoplaced yes)
		(property "Reference" "R90"
			(at 52.07 243.205 0)
			(effects
				(font
					(size 1.27 1.27)
				)
				(justify right bottom)
			)
		)
		(property "Value" "R_0R_0402"
			(at 72.39 256.54 0)
			(effects
				(font
					(size 1.27 1.27)
					(thickness 0.15)
				)
				(justify left bottom)
				(hide yes)
			)
		)
		(property "Footprint" "antmicro-footprints:R_0402_1005Metric"
			(at 72.39 259.08 0)
			(effects
				(font
					(size 1.27 1.27)
					(thickness 0.15)
				)
				(justify left bottom)
				(hide yes)
			)
		)
		(property "Datasheet" "https://industrial.panasonic.com/cdbs/www-data/pdf/RDA0000/AOA0000C301.pdf"
			(at 72.39 261.62 0)
			(effects
				(font
					(size 1.27 1.27)
					(thickness 0.15)
				)
				(justify left bottom)
				(hide yes)
			)
		)
		(property "Description" "SMD Chip Resistor, Jumper, 0 ohm, 100 mW, 0402 [1005 Metric], Thick Film, General Purpose"
			(at 52.07 243.84 0)
			(effects
				(font
					(size 1.27 1.27)
				)
				(hide yes)
			)
		)
		(property "Manufacturer" "Panasonic"
			(at 72.39 266.7 0)
			(effects
				(font
					(size 1.27 1.27)
					(thickness 0.15)
				)
				(justify left bottom)
				(hide yes)
			)
		)
		(property "MPN" "ERJ2GE0R00X"
			(at 72.39 264.16 0)
			(effects
				(font
					(size 1.27 1.27)
					(thickness 0.15)
				)
				(justify left bottom)
				(hide yes)
			)
		)
		(property "Val" "0R"
			(at 59.69 243.205 0)
			(effects
				(font
					(size 1.27 1.27)
					(thickness 0.15)
				)
				(justify right bottom)
			)
		)
		(property "License" "Apache-2.0"
			(at 72.39 269.24 0)
			(effects
				(font
					(size 1.27 1.27)
					(thickness 0.15)
				)
				(justify left bottom)
				(hide yes)
			)
		)
		(property "Author" "Antmicro"
			(at 72.39 271.78 0)
			(effects
				(font
					(size 1.27 1.27)
					(thickness 0.15)
				)
				(justify left bottom)
				(hide yes)
			)
		)
		(property "Tolerance" "~"
			(at 72.39 254 0)
			(effects
				(font
					(size 1.27 1.27)
				)
				(justify left bottom)
				(hide yes)
			)
		)
		(property "Current" "1A"
			(at 72.39 274.32 0)
			(effects
				(font
					(size 1.27 1.27)
					(thickness 0.15)
				)
				(justify left bottom)
				(hide yes)
			)
		)
		(pin "1"
		)
		(pin "2"
		)
		(instances
			(project "jetson-agx-thor-baseboard"
				(path ""
					(reference "R90")
					(unit 1)
				)
			)
		)
	)
	(symbol
		(lib_id "antmicropower:+3V3")
		(at 87.63 224.79 0)
		(unit 1)
		(exclude_from_sim no)
		(in_bom yes)
		(on_board yes)
		(dnp no)
		(fields_autoplaced yes)
		(property "Reference" "#PWR0204"
			(at 102.87 224.79 0)
			(effects
				(font
					(size 1.27 1.27)
					(thickness 0.15)
				)
				(justify left bottom)
				(hide yes)
			)
		)
		(property "Value" "FLASH_PWR"
			(at 87.63 219.71 0)
			(effects
				(font
					(size 1.27 1.27)
					(thickness 0.15)
				)
			)
		)
		(property "Footprint" ""
			(at 102.87 232.41 0)
			(effects
				(font
					(size 1.27 1.27)
					(thickness 0.15)
				)
				(justify left bottom)
				(hide yes)
			)
		)
		(property "Datasheet" ""
			(at 102.87 234.95 0)
			(effects
				(font
					(size 1.27 1.27)
					(thickness 0.15)
				)
				(justify left bottom)
				(hide yes)
			)
		)
		(property "Description" ""
			(at 87.63 224.79 0)
			(effects
				(font
					(size 1.27 1.27)
				)
				(hide yes)
			)
		)
		(property "Author" "Antmicro"
			(at 102.87 227.33 0)
			(effects
				(font
					(size 1.27 1.27)
					(thickness 0.15)
				)
				(justify left bottom)
				(hide yes)
			)
		)
		(property "License" "Apache-2.0"
			(at 102.87 229.87 0)
			(effects
				(font
					(size 1.27 1.27)
					(thickness 0.15)
				)
				(justify left bottom)
				(hide yes)
			)
		)
		(pin "1"
		)
		(instances
			(project "jetson-agx-thor-baseboard"
				(path ""
					(reference "#PWR0204")
					(unit 1)
				)
			)
		)
	)
	(symbol
		(lib_id "antmicroCapacitors0402:C_100n_0402")
		(at 48.26 48.26 90)
		(unit 1)
		(exclude_from_sim no)
		(in_bom yes)
		(on_board yes)
		(dnp no)
		(fields_autoplaced yes)
		(property "Reference" "C88"
			(at 50.8 44.4436 90)
			(effects
				(font
					(size 1.27 1.27)
					(thickness 0.15)
				)
				(justify right)
			)
		)
		(property "Value" "C_100n_0402"
			(at 71.12 33.02 0)
			(effects
				(font
					(size 1.27 1.27)
					(thickness 0.15)
				)
				(justify left bottom)
				(hide yes)
			)
		)
		(property "Footprint" "antmicro-footprints:C_0402_1005Metric"
			(at 73.66 33.02 0)
			(effects
				(font
					(size 1.27 1.27)
					(thickness 0.15)
				)
				(justify left bottom)
				(hide yes)
			)
		)
		(property "Datasheet" "https://www.murata.com/products/productdetail?partno=GRM155R61H104KE14%23"
			(at 76.2 33.02 0)
			(effects
				(font
					(size 1.27 1.27)
					(thickness 0.15)
				)
				(justify left bottom)
				(hide yes)
			)
		)
		(property "Description" "SMD Multilayer Ceramic Capacitor, 0.1 µF, 50 V, 0402 [1005 Metric], ± 10%, X5R, GRM Series"
			(at 48.26 48.26 0)
			(effects
				(font
					(size 1.27 1.27)
				)
				(hide yes)
			)
		)
		(property "MPN" "GRM155R61H104KE14D"
			(at 78.74 33.02 0)
			(effects
				(font
					(size 1.27 1.27)
					(thickness 0.15)
				)
				(justify left bottom)
				(hide yes)
			)
		)
		(property "Val" "100n"
			(at 50.8 46.9836 90)
			(effects
				(font
					(size 1.27 1.27)
					(thickness 0.15)
				)
				(justify right)
			)
		)
		(property "Voltage" "50V"
			(at 58.42 33.02 0)
			(effects
				(font
					(size 1.27 1.27)
					(thickness 0.15)
				)
				(justify left bottom)
				(hide yes)
			)
		)
		(property "Dielectric" "X5R"
			(at 60.96 33.02 0)
			(effects
				(font
					(size 1.27 1.27)
					(thickness 0.15)
				)
				(justify left bottom)
				(hide yes)
			)
		)
		(property "Manufacturer" "Murata"
			(at 63.5 33.02 0)
			(effects
				(font
					(size 1.27 1.27)
					(thickness 0.15)
				)
				(justify left bottom)
				(hide yes)
			)
		)
		(property "License" "Apache-2.0"
			(at 66.04 33.02 0)
			(effects
				(font
					(size 1.27 1.27)
					(thickness 0.15)
				)
				(justify left bottom)
				(hide yes)
			)
		)
		(property "Author" "Antmicro"
			(at 68.58 33.02 0)
			(effects
				(font
					(size 1.27 1.27)
					(thickness 0.15)
				)
				(justify left bottom)
				(hide yes)
			)
		)
		(pin "1"
		)
		(pin "2"
		)
		(instances
			(project "jetson-agx-thor-baseboard"
				(path ""
					(reference "C88")
					(unit 1)
				)
			)
		)
	)
	(symbol
		(lib_id "antmicropower:GND")
		(at 308.61 113.03 0)
		(unit 1)
		(exclude_from_sim no)
		(in_bom yes)
		(on_board yes)
		(dnp no)
		(property "Reference" "#PWR0210"
			(at 308.61 119.38 0)
			(effects
				(font
					(size 1.27 1.27)
				)
				(justify left bottom)
				(hide yes)
			)
		)
		(property "Value" "GND"
			(at 308.61 116.84 0)
			(effects
				(font
					(size 1.27 1.27)
					(thickness 0.15)
				)
			)
		)
		(property "Footprint" ""
			(at 317.5 120.65 0)
			(effects
				(font
					(size 1.27 1.27)
					(thickness 0.15)
				)
				(justify left bottom)
				(hide yes)
			)
		)
		(property "Datasheet" ""
			(at 317.5 125.73 0)
			(effects
				(font
					(size 1.27 1.27)
					(thickness 0.15)
				)
				(justify left bottom)
				(hide yes)
			)
		)
		(property "Description" ""
			(at 308.61 113.03 0)
			(effects
				(font
					(size 1.27 1.27)
				)
				(hide yes)
			)
		)
		(property "Author" "Antmicro"
			(at 317.5 120.65 0)
			(effects
				(font
					(size 1.27 1.27)
					(thickness 0.15)
				)
				(justify left bottom)
				(hide yes)
			)
		)
		(property "License" "Apache-2.0"
			(at 317.5 123.19 0)
			(effects
				(font
					(size 1.27 1.27)
					(thickness 0.15)
				)
				(justify left bottom)
				(hide yes)
			)
		)
		(pin "1"
		)
		(instances
			(project "jetson-agx-thor-baseboard"
				(path ""
					(reference "#PWR0210")
					(unit 1)
				)
			)
		)
	)
	(symbol
		(lib_id "antmicroResistors0402:R_200k_0402")
		(at 236.22 195.58 270)
		(mirror x)
		(unit 1)
		(exclude_from_sim no)
		(in_bom yes)
		(on_board yes)
		(dnp no)
		(property "Reference" "R322"
			(at 235.204 191.77 90)
			(effects
				(font
					(size 1.27 1.27)
					(thickness 0.15)
				)
				(justify right)
			)
		)
		(property "Value" "R_200k_0402"
			(at 223.52 175.26 0)
			(effects
				(font
					(size 1.27 1.27)
					(thickness 0.15)
				)
				(justify left bottom)
				(hide yes)
			)
		)
		(property "Footprint" "antmicro-footprints:R_0402_1005Metric"
			(at 220.98 175.26 0)
			(effects
				(font
					(size 1.27 1.27)
					(thickness 0.15)
				)
				(justify left bottom)
				(hide yes)
			)
		)
		(property "Datasheet" "https://www.bourns.com/docs/product-datasheets/cr.pdf"
			(at 218.44 175.26 0)
			(effects
				(font
					(size 1.27 1.27)
					(thickness 0.15)
				)
				(justify left bottom)
				(hide yes)
			)
		)
		(property "Description" "SMD Chip Resistor, 200 kohm, ± 1%, 62.5 mW, 0402 [1005 Metric], Thick Film, General Purpose"
			(at 236.22 195.58 0)
			(effects
				(font
					(size 1.27 1.27)
				)
				(hide yes)
			)
		)
		(property "MPN" "CR0402-FX-2003GLF"
			(at 215.9 175.26 0)
			(effects
				(font
					(size 1.27 1.27)
					(thickness 0.15)
				)
				(justify left bottom)
				(hide yes)
			)
		)
		(property "Manufacturer" "Bourns"
			(at 213.36 175.26 0)
			(effects
				(font
					(size 1.27 1.27)
					(thickness 0.15)
				)
				(justify left bottom)
				(hide yes)
			)
		)
		(property "License" "Apache-2.0"
			(at 210.82 175.26 0)
			(effects
				(font
					(size 1.27 1.27)
					(thickness 0.15)
				)
				(justify left bottom)
				(hide yes)
			)
		)
		(property "Author" "Antmicro"
			(at 208.28 175.26 0)
			(effects
				(font
					(size 1.27 1.27)
					(thickness 0.15)
				)
				(justify left bottom)
				(hide yes)
			)
		)
		(property "Val" "200k"
			(at 235.204 194.31 90)
			(effects
				(font
					(size 1.27 1.27)
					(thickness 0.15)
				)
				(justify right)
			)
		)
		(property "Tolerance" "1%"
			(at 226.06 175.26 0)
			(effects
				(font
					(size 1.27 1.27)
				)
				(justify left bottom)
				(hide yes)
			)
		)
		(pin "1"
		)
		(pin "2"
		)
		(instances
			(project "jetson-agx-thor-baseboard"
				(path ""
					(reference "R322")
					(unit 1)
				)
			)
		)
	)
	(symbol
		(lib_id "antmicropower:GND")
		(at 124.46 189.23 0)
		(mirror y)
		(unit 1)
		(exclude_from_sim no)
		(in_bom yes)
		(on_board yes)
		(dnp no)
		(property "Reference" "#PWR0198"
			(at 124.46 195.58 0)
			(effects
				(font
					(size 1.27 1.27)
				)
				(justify left bottom)
				(hide yes)
			)
		)
		(property "Value" "GND"
			(at 124.46 193.04 0)
			(effects
				(font
					(size 1.27 1.27)
					(thickness 0.15)
				)
			)
		)
		(property "Footprint" ""
			(at 115.57 196.85 0)
			(effects
				(font
					(size 1.27 1.27)
					(thickness 0.15)
				)
				(justify left bottom)
				(hide yes)
			)
		)
		(property "Datasheet" ""
			(at 115.57 201.93 0)
			(effects
				(font
					(size 1.27 1.27)
					(thickness 0.15)
				)
				(justify left bottom)
				(hide yes)
			)
		)
		(property "Description" ""
			(at 124.46 189.23 0)
			(effects
				(font
					(size 1.27 1.27)
				)
				(hide yes)
			)
		)
		(property "Author" "Antmicro"
			(at 115.57 196.85 0)
			(effects
				(font
					(size 1.27 1.27)
					(thickness 0.15)
				)
				(justify left bottom)
				(hide yes)
			)
		)
		(property "License" "Apache-2.0"
			(at 115.57 199.39 0)
			(effects
				(font
					(size 1.27 1.27)
					(thickness 0.15)
				)
				(justify left bottom)
				(hide yes)
			)
		)
		(pin "1"
		)
		(instances
			(project "jetson-agx-thor-baseboard"
				(path ""
					(reference "#PWR0198")
					(unit 1)
				)
			)
		)
	)
	(symbol
		(lib_id "antmicroResistors0402:R_2k2_0402")
		(at 336.55 162.56 90)
		(unit 1)
		(exclude_from_sim no)
		(in_bom yes)
		(on_board yes)
		(dnp no)
		(property "Reference" "R259"
			(at 337.82 158.75 90)
			(effects
				(font
					(size 1.27 1.27)
				)
				(justify right)
			)
		)
		(property "Value" "R_2k2_0402"
			(at 349.25 142.24 0)
			(effects
				(font
					(size 1.27 1.27)
					(thickness 0.15)
				)
				(justify left bottom)
				(hide yes)
			)
		)
		(property "Footprint" "antmicro-footprints:R_0402_1005Metric"
			(at 351.79 142.24 0)
			(effects
				(font
					(size 1.27 1.27)
					(thickness 0.15)
				)
				(justify left bottom)
				(hide yes)
			)
		)
		(property "Datasheet" "https://www.bourns.com/docs/product-datasheets/cr.pdf"
			(at 354.33 142.24 0)
			(effects
				(font
					(size 1.27 1.27)
					(thickness 0.15)
				)
				(justify left bottom)
				(hide yes)
			)
		)
		(property "Description" "SMD Chip Resistor, 2.2 kohm, ± 1%, 62.5 mW, 0402 [1005 Metric], Thick Film, General Purpose"
			(at 336.55 162.56 0)
			(effects
				(font
					(size 1.27 1.27)
				)
				(hide yes)
			)
		)
		(property "Manufacturer" "Bourns"
			(at 359.41 142.24 0)
			(effects
				(font
					(size 1.27 1.27)
					(thickness 0.15)
				)
				(justify left bottom)
				(hide yes)
			)
		)
		(property "MPN" "CR0402-FX-2201GLF"
			(at 356.87 142.24 0)
			(effects
				(font
					(size 1.27 1.27)
					(thickness 0.15)
				)
				(justify left bottom)
				(hide yes)
			)
		)
		(property "Val" "2k2"
			(at 337.82 161.29 90)
			(effects
				(font
					(size 1.27 1.27)
					(thickness 0.15)
				)
				(justify right)
			)
		)
		(property "License" "Apache-2.0"
			(at 361.95 142.24 0)
			(effects
				(font
					(size 1.27 1.27)
					(thickness 0.15)
				)
				(justify left bottom)
				(hide yes)
			)
		)
		(property "Author" "Antmicro"
			(at 364.49 142.24 0)
			(effects
				(font
					(size 1.27 1.27)
					(thickness 0.15)
				)
				(justify left bottom)
				(hide yes)
			)
		)
		(property "Tolerance" "1%"
			(at 346.71 142.24 0)
			(effects
				(font
					(size 1.27 1.27)
				)
				(justify left bottom)
				(hide yes)
			)
		)
		(pin "1"
		)
		(pin "2"
		)
		(instances
			(project "jetson-agx-thor-baseboard"
				(path ""
					(reference "R259")
					(unit 1)
				)
			)
		)
	)
	(symbol
		(lib_id "antmicroCapacitors0402:C_100n_0402")
		(at 99.06 48.26 90)
		(unit 1)
		(exclude_from_sim no)
		(in_bom yes)
		(on_board yes)
		(dnp no)
		(fields_autoplaced yes)
		(property "Reference" "C99"
			(at 101.6 44.4436 90)
			(effects
				(font
					(size 1.27 1.27)
					(thickness 0.15)
				)
				(justify right)
			)
		)
		(property "Value" "C_100n_0402"
			(at 121.92 33.02 0)
			(effects
				(font
					(size 1.27 1.27)
					(thickness 0.15)
				)
				(justify left bottom)
				(hide yes)
			)
		)
		(property "Footprint" "antmicro-footprints:C_0402_1005Metric"
			(at 124.46 33.02 0)
			(effects
				(font
					(size 1.27 1.27)
					(thickness 0.15)
				)
				(justify left bottom)
				(hide yes)
			)
		)
		(property "Datasheet" "https://www.murata.com/products/productdetail?partno=GRM155R61H104KE14%23"
			(at 127 33.02 0)
			(effects
				(font
					(size 1.27 1.27)
					(thickness 0.15)
				)
				(justify left bottom)
				(hide yes)
			)
		)
		(property "Description" "SMD Multilayer Ceramic Capacitor, 0.1 µF, 50 V, 0402 [1005 Metric], ± 10%, X5R, GRM Series"
			(at 99.06 48.26 0)
			(effects
				(font
					(size 1.27 1.27)
				)
				(hide yes)
			)
		)
		(property "MPN" "GRM155R61H104KE14D"
			(at 129.54 33.02 0)
			(effects
				(font
					(size 1.27 1.27)
					(thickness 0.15)
				)
				(justify left bottom)
				(hide yes)
			)
		)
		(property "Val" "100n"
			(at 101.6 46.9836 90)
			(effects
				(font
					(size 1.27 1.27)
					(thickness 0.15)
				)
				(justify right)
			)
		)
		(property "Voltage" "50V"
			(at 109.22 33.02 0)
			(effects
				(font
					(size 1.27 1.27)
					(thickness 0.15)
				)
				(justify left bottom)
				(hide yes)
			)
		)
		(property "Dielectric" "X5R"
			(at 111.76 33.02 0)
			(effects
				(font
					(size 1.27 1.27)
					(thickness 0.15)
				)
				(justify left bottom)
				(hide yes)
			)
		)
		(property "Manufacturer" "Murata"
			(at 114.3 33.02 0)
			(effects
				(font
					(size 1.27 1.27)
					(thickness 0.15)
				)
				(justify left bottom)
				(hide yes)
			)
		)
		(property "License" "Apache-2.0"
			(at 116.84 33.02 0)
			(effects
				(font
					(size 1.27 1.27)
					(thickness 0.15)
				)
				(justify left bottom)
				(hide yes)
			)
		)
		(property "Author" "Antmicro"
			(at 119.38 33.02 0)
			(effects
				(font
					(size 1.27 1.27)
					(thickness 0.15)
				)
				(justify left bottom)
				(hide yes)
			)
		)
		(pin "1"
		)
		(pin "2"
		)
		(instances
			(project "jetson-agx-thor-baseboard"
				(path ""
					(reference "C99")
					(unit 1)
				)
			)
		)
	)
	(symbol
		(lib_id "antmicropower:GND")
		(at 313.69 176.53 0)
		(mirror y)
		(unit 1)
		(exclude_from_sim no)
		(in_bom yes)
		(on_board yes)
		(dnp no)
		(property "Reference" "#PWR0205"
			(at 313.69 182.88 0)
			(effects
				(font
					(size 1.27 1.27)
				)
				(justify left bottom)
				(hide yes)
			)
		)
		(property "Value" "GND"
			(at 313.69 180.34 0)
			(effects
				(font
					(size 1.27 1.27)
					(thickness 0.15)
				)
			)
		)
		(property "Footprint" ""
			(at 304.8 184.15 0)
			(effects
				(font
					(size 1.27 1.27)
					(thickness 0.15)
				)
				(justify left bottom)
				(hide yes)
			)
		)
		(property "Datasheet" ""
			(at 304.8 189.23 0)
			(effects
				(font
					(size 1.27 1.27)
					(thickness 0.15)
				)
				(justify left bottom)
				(hide yes)
			)
		)
		(property "Description" ""
			(at 313.69 176.53 0)
			(effects
				(font
					(size 1.27 1.27)
				)
				(hide yes)
			)
		)
		(property "Author" "Antmicro"
			(at 304.8 184.15 0)
			(effects
				(font
					(size 1.27 1.27)
					(thickness 0.15)
				)
				(justify left bottom)
				(hide yes)
			)
		)
		(property "License" "Apache-2.0"
			(at 304.8 186.69 0)
			(effects
				(font
					(size 1.27 1.27)
					(thickness 0.15)
				)
				(justify left bottom)
				(hide yes)
			)
		)
		(pin "1"
		)
		(instances
			(project "jetson-agx-thor-baseboard"
				(path ""
					(reference "#PWR0205")
					(unit 1)
				)
			)
		)
	)
	(symbol
		(lib_id "antmicroResistors0402:R_2k2_0402")
		(at 337.82 40.64 90)
		(unit 1)
		(exclude_from_sim no)
		(in_bom yes)
		(on_board yes)
		(dnp no)
		(property "Reference" "R73"
			(at 339.09 36.83 90)
			(effects
				(font
					(size 1.27 1.27)
				)
				(justify right)
			)
		)
		(property "Value" "R_2k2_0402"
			(at 350.52 20.32 0)
			(effects
				(font
					(size 1.27 1.27)
					(thickness 0.15)
				)
				(justify left bottom)
				(hide yes)
			)
		)
		(property "Footprint" "antmicro-footprints:R_0402_1005Metric"
			(at 353.06 20.32 0)
			(effects
				(font
					(size 1.27 1.27)
					(thickness 0.15)
				)
				(justify left bottom)
				(hide yes)
			)
		)
		(property "Datasheet" "https://www.bourns.com/docs/product-datasheets/cr.pdf"
			(at 355.6 20.32 0)
			(effects
				(font
					(size 1.27 1.27)
					(thickness 0.15)
				)
				(justify left bottom)
				(hide yes)
			)
		)
		(property "Description" "SMD Chip Resistor, 2.2 kohm, ± 1%, 62.5 mW, 0402 [1005 Metric], Thick Film, General Purpose"
			(at 337.82 40.64 0)
			(effects
				(font
					(size 1.27 1.27)
				)
				(hide yes)
			)
		)
		(property "Manufacturer" "Bourns"
			(at 360.68 20.32 0)
			(effects
				(font
					(size 1.27 1.27)
					(thickness 0.15)
				)
				(justify left bottom)
				(hide yes)
			)
		)
		(property "MPN" "CR0402-FX-2201GLF"
			(at 358.14 20.32 0)
			(effects
				(font
					(size 1.27 1.27)
					(thickness 0.15)
				)
				(justify left bottom)
				(hide yes)
			)
		)
		(property "Val" "2k2"
			(at 339.09 39.37 90)
			(effects
				(font
					(size 1.27 1.27)
					(thickness 0.15)
				)
				(justify right)
			)
		)
		(property "License" "Apache-2.0"
			(at 363.22 20.32 0)
			(effects
				(font
					(size 1.27 1.27)
					(thickness 0.15)
				)
				(justify left bottom)
				(hide yes)
			)
		)
		(property "Author" "Antmicro"
			(at 365.76 20.32 0)
			(effects
				(font
					(size 1.27 1.27)
					(thickness 0.15)
				)
				(justify left bottom)
				(hide yes)
			)
		)
		(property "Tolerance" "1%"
			(at 347.98 20.32 0)
			(effects
				(font
					(size 1.27 1.27)
				)
				(justify left bottom)
				(hide yes)
			)
		)
		(pin "1"
		)
		(pin "2"
		)
		(instances
			(project "jetson-agx-thor-baseboard"
				(path ""
					(reference "R73")
					(unit 1)
				)
			)
		)
	)
	(symbol
		(lib_id "antmicroTVSDiodes:PESD5Z5_0F")
		(at 373.38 154.94 270)
		(unit 1)
		(exclude_from_sim no)
		(in_bom yes)
		(on_board yes)
		(dnp no)
		(property "Reference" "D48"
			(at 374.65 156.21 90)
			(effects
				(font
					(size 1.27 1.27)
				)
				(justify left)
			)
		)
		(property "Value" "PESD5Z5.0F"
			(at 358.14 176.53 0)
			(effects
				(font
					(size 1.27 1.27)
					(thickness 0.15)
				)
				(justify left bottom)
				(hide yes)
			)
		)
		(property "Footprint" "antmicro-footprints:SOD-523"
			(at 368.3 170.18 0)
			(effects
				(font
					(size 1.27 1.27)
					(thickness 0.15)
				)
				(justify left bottom)
				(hide yes)
			)
		)
		(property "Datasheet" "https://assets.nexperia.com/documents/data-sheet/PESD5Z5_0.pdf"
			(at 365.76 170.18 0)
			(effects
				(font
					(size 1.27 1.27)
					(thickness 0.15)
				)
				(justify left bottom)
				(hide yes)
			)
		)
		(property "Description" "Unidirectional TVS, 30 kV,  SOD-523, 5 V, 89 pF"
			(at 353.06 170.18 0)
			(effects
				(font
					(size 1.27 1.27)
				)
				(justify left bottom)
				(hide yes)
			)
		)
		(property "Manufacturer" "Nexperia"
			(at 363.22 170.18 0)
			(effects
				(font
					(size 1.27 1.27)
					(thickness 0.15)
				)
				(justify left bottom)
				(hide yes)
			)
		)
		(property "MPN" "PESD5Z5.0F"
			(at 374.65 159.004 90)
			(effects
				(font
					(size 1.27 1.27)
					(thickness 0.15)
				)
				(justify left bottom)
			)
		)
		(property "Author" "Antmicro"
			(at 358.14 170.18 0)
			(effects
				(font
					(size 1.27 1.27)
					(thickness 0.15)
				)
				(justify left bottom)
				(hide yes)
			)
		)
		(property "License" "Apache-2.0"
			(at 355.6 170.18 0)
			(effects
				(font
					(size 1.27 1.27)
					(thickness 0.15)
				)
				(justify left bottom)
				(hide yes)
			)
		)
		(pin "1"
		)
		(pin "2"
		)
		(instances
			(project "jetson-agx-thor-baseboard"
				(path ""
					(reference "D48")
					(unit 1)
				)
			)
		)
	)
	(symbol
		(lib_id "antmicroTransistorsFETsMOSFETsArrays:DMC2400UV-7")
		(at 165.1 265.43 180)
		(unit 1)
		(exclude_from_sim no)
		(in_bom yes)
		(on_board yes)
		(dnp no)
		(property "Reference" "Q26"
			(at 158.75 268.478 0)
			(effects
				(font
					(size 1.27 1.27)
					(thickness 0.15)
				)
			)
		)
		(property "Value" "DMC2400UV-7"
			(at 137.16 260.35 0)
			(effects
				(font
					(size 1.27 1.27)
					(thickness 0.15)
				)
				(justify left bottom)
				(hide yes)
			)
		)
		(property "Footprint" "antmicro-footprints:SOT-563"
			(at 137.16 257.81 0)
			(effects
				(font
					(size 1.27 1.27)
					(thickness 0.15)
				)
				(justify left bottom)
				(hide yes)
			)
		)
		(property "Datasheet" "https://www.mouser.com/datasheet/2/115/DIOD_S_A0010038249_1-2543538.pdf"
			(at 137.16 255.27 0)
			(effects
				(font
					(size 1.27 1.27)
					(thickness 0.15)
				)
				(justify left bottom)
				(hide yes)
			)
		)
		(property "Description" "Dual MOSFET, Complementary N and P Channel, 20 V, 20 V, 1.03 A, 1.03 A, 0.3 ohm"
			(at 137.16 242.57 0)
			(effects
				(font
					(size 1.27 1.27)
				)
				(justify left bottom)
				(hide yes)
			)
		)
		(property "MPN" "DMC2400UV-7"
			(at 158.75 271.018 0)
			(effects
				(font
					(size 1.27 1.27)
					(thickness 0.15)
				)
			)
		)
		(property "Manufacturer" "Diodes Incorporated"
			(at 137.16 250.19 0)
			(effects
				(font
					(size 1.27 1.27)
					(thickness 0.15)
				)
				(justify left bottom)
				(hide yes)
			)
		)
		(property "Author" "Antmicro"
			(at 137.16 247.65 0)
			(effects
				(font
					(size 1.27 1.27)
					(thickness 0.15)
				)
				(justify left bottom)
				(hide yes)
			)
		)
		(property "License" "Apache-2.0"
			(at 137.16 245.11 0)
			(effects
				(font
					(size 1.27 1.27)
					(thickness 0.15)
				)
				(justify left bottom)
				(hide yes)
			)
		)
		(pin "5"
		)
		(pin "3"
		)
		(pin "6"
		)
		(pin "2"
		)
		(pin "1"
		)
		(pin "4"
		)
		(instances
			(project "jetson-agx-thor-baseboard"
				(path ""
					(reference "Q26")
					(unit 1)
				)
			)
		)
	)
	(symbol
		(lib_id "antmicroTVSDiodes:TPD4E05U06QDQARQ1")
		(at 323.85 176.53 270)
		(mirror x)
		(unit 1)
		(exclude_from_sim no)
		(in_bom yes)
		(on_board yes)
		(dnp no)
		(property "Reference" "U25"
			(at 317.246 163.322 90)
			(effects
				(font
					(size 1.27 1.27)
				)
				(justify left)
			)
		)
		(property "Value" "TPD4E05U06QDQARQ1"
			(at 313.69 152.4 0)
			(effects
				(font
					(size 1.27 1.27)
					(thickness 0.15)
				)
				(justify left bottom)
				(hide yes)
			)
		)
		(property "Footprint" "antmicro-footprints:USON-10_2.5x1mm_P0.5mm"
			(at 318.77 152.4 0)
			(effects
				(font
					(size 1.27 1.27)
					(thickness 0.15)
				)
				(justify left bottom)
				(hide yes)
			)
		)
		(property "Datasheet" "https://www.ti.com/lit/ds/symlink/tpd4e05u06-q1.pdf?HQS=dis-mous-null-mousermode-dsf-pf-null-wwe&ts=1663591265741&ref_url=https%253A%252F%252Fwww.mouser.com%252F"
			(at 316.23 152.4 0)
			(effects
				(font
					(size 1.27 1.27)
					(thickness 0.15)
				)
				(justify left bottom)
				(hide yes)
			)
		)
		(property "Description" "TVS diode array, 12 kV, USON-10, 5.5 V, 0.5 pF"
			(at 323.85 176.53 0)
			(effects
				(font
					(size 1.27 1.27)
				)
				(hide yes)
			)
		)
		(property "Manufacturer" "Texas Instruments"
			(at 311.15 152.4 0)
			(effects
				(font
					(size 1.27 1.27)
					(thickness 0.15)
				)
				(justify left bottom)
				(hide yes)
			)
		)
		(property "MPN" "TPD4E05U06QDQARQ1"
			(at 309.626 165.8621 90)
			(effects
				(font
					(size 1.27 1.27)
					(thickness 0.15)
				)
				(justify left)
			)
		)
		(property "Author" "Antmicro"
			(at 308.61 152.4 0)
			(effects
				(font
					(size 1.27 1.27)
					(thickness 0.15)
				)
				(justify left bottom)
				(hide yes)
			)
		)
		(property "License" "Apache-2.0"
			(at 306.07 152.4 0)
			(effects
				(font
					(size 1.27 1.27)
					(thickness 0.15)
				)
				(justify left bottom)
				(hide yes)
			)
		)
		(pin "1"
		)
		(pin "10"
		)
		(pin "2"
		)
		(pin "3"
		)
		(pin "4"
		)
		(pin "5"
		)
		(pin "6"
		)
		(pin "7"
		)
		(pin "8"
		)
		(pin "9"
		)
		(instances
			(project "jetson-agx-thor-baseboard"
				(path ""
					(reference "U25")
					(unit 1)
				)
			)
		)
	)
	(symbol
		(lib_id "antmicropower:GND")
		(at 312.42 54.61 0)
		(mirror y)
		(unit 1)
		(exclude_from_sim no)
		(in_bom yes)
		(on_board yes)
		(dnp no)
		(property "Reference" "#PWR0206"
			(at 312.42 60.96 0)
			(effects
				(font
					(size 1.27 1.27)
				)
				(justify left bottom)
				(hide yes)
			)
		)
		(property "Value" "GND"
			(at 312.42 58.42 0)
			(effects
				(font
					(size 1.27 1.27)
					(thickness 0.15)
				)
			)
		)
		(property "Footprint" ""
			(at 303.53 62.23 0)
			(effects
				(font
					(size 1.27 1.27)
					(thickness 0.15)
				)
				(justify left bottom)
				(hide yes)
			)
		)
		(property "Datasheet" ""
			(at 303.53 67.31 0)
			(effects
				(font
					(size 1.27 1.27)
					(thickness 0.15)
				)
				(justify left bottom)
				(hide yes)
			)
		)
		(property "Description" ""
			(at 312.42 54.61 0)
			(effects
				(font
					(size 1.27 1.27)
				)
				(hide yes)
			)
		)
		(property "Author" "Antmicro"
			(at 303.53 62.23 0)
			(effects
				(font
					(size 1.27 1.27)
					(thickness 0.15)
				)
				(justify left bottom)
				(hide yes)
			)
		)
		(property "License" "Apache-2.0"
			(at 303.53 64.77 0)
			(effects
				(font
					(size 1.27 1.27)
					(thickness 0.15)
				)
				(justify left bottom)
				(hide yes)
			)
		)
		(pin "1"
		)
		(instances
			(project "jetson-agx-thor-baseboard"
				(path ""
					(reference "#PWR0206")
					(unit 1)
				)
			)
		)
	)
	(symbol
		(lib_id "antmicroResistors0402:R_10k_0402")
		(at 148.59 232.41 90)
		(mirror x)
		(unit 1)
		(exclude_from_sim no)
		(in_bom yes)
		(on_board yes)
		(dnp no)
		(property "Reference" "R299"
			(at 142.24 233.68 90)
			(effects
				(font
					(size 1.27 1.27)
					(thickness 0.15)
				)
				(justify right)
			)
		)
		(property "Value" "R_10k_0402"
			(at 161.29 252.73 0)
			(effects
				(font
					(size 1.27 1.27)
					(thickness 0.15)
				)
				(justify left bottom)
				(hide yes)
			)
		)
		(property "Footprint" "antmicro-footprints:R_0402_1005Metric"
			(at 163.83 252.73 0)
			(effects
				(font
					(size 1.27 1.27)
					(thickness 0.15)
				)
				(justify left bottom)
				(hide yes)
			)
		)
		(property "Datasheet" "https://www.bourns.com/docs/product-datasheets/cr.pdf"
			(at 166.37 252.73 0)
			(effects
				(font
					(size 1.27 1.27)
					(thickness 0.15)
				)
				(justify left bottom)
				(hide yes)
			)
		)
		(property "Description" "SMD Chip Resistor, 10 kohm, ± 1%, 62.5 mW, 0402 [1005 Metric], Thick Film, General Purpose"
			(at 148.59 232.41 0)
			(effects
				(font
					(size 1.27 1.27)
				)
				(hide yes)
			)
		)
		(property "MPN" "CR0402-FX-1002GLF"
			(at 168.91 252.73 0)
			(effects
				(font
					(size 1.27 1.27)
					(thickness 0.15)
				)
				(justify left bottom)
				(hide yes)
			)
		)
		(property "Manufacturer" "Bourns"
			(at 171.45 252.73 0)
			(effects
				(font
					(size 1.27 1.27)
					(thickness 0.15)
				)
				(justify left bottom)
				(hide yes)
			)
		)
		(property "License" "Apache-2.0"
			(at 173.99 252.73 0)
			(effects
				(font
					(size 1.27 1.27)
					(thickness 0.15)
				)
				(justify left bottom)
				(hide yes)
			)
		)
		(property "Author" "Antmicro"
			(at 176.53 252.73 0)
			(effects
				(font
					(size 1.27 1.27)
					(thickness 0.15)
				)
				(justify left bottom)
				(hide yes)
			)
		)
		(property "Val" "10k"
			(at 143.51 236.22 90)
			(effects
				(font
					(size 1.27 1.27)
					(thickness 0.15)
				)
				(justify right)
			)
		)
		(property "Tolerance" "1%"
			(at 158.75 252.73 0)
			(effects
				(font
					(size 1.27 1.27)
				)
				(justify left bottom)
				(hide yes)
			)
		)
		(pin "2"
		)
		(pin "1"
		)
		(instances
			(project "jetson-agx-thor-baseboard"
				(path ""
					(reference "R299")
					(unit 1)
				)
			)
		)
	)
	(symbol
		(lib_id "antmicroTestPoints:TP_0.75mm_SMD")
		(at 114.3 127 180)
		(unit 1)
		(exclude_from_sim no)
		(in_bom no)
		(on_board yes)
		(dnp no)
		(property "Reference" "TP2"
			(at 110.236 126.238 0)
			(effects
				(font
					(size 1.27 1.27)
				)
				(justify left bottom)
			)
		)
		(property "Value" "TP_0.75mm_SMD"
			(at 104.14 123.19 0)
			(effects
				(font
					(size 1.27 1.27)
					(thickness 0.15)
				)
				(justify left bottom)
				(hide yes)
			)
		)
		(property "Footprint" "antmicro-footprints:TP_SMD_0.75mm"
			(at 104.14 120.65 0)
			(effects
				(font
					(size 1.27 1.27)
					(thickness 0.15)
				)
				(justify left bottom)
				(hide yes)
			)
		)
		(property "Datasheet" ""
			(at 96.52 114.3 0)
			(effects
				(font
					(size 1.27 1.27)
					(thickness 0.15)
				)
				(justify left bottom)
				(hide yes)
			)
		)
		(property "Description" "SMT test point"
			(at 114.3 127 0)
			(effects
				(font
					(size 1.27 1.27)
				)
				(hide yes)
			)
		)
		(property "MPN" ""
			(at 103.505 115.57 0)
			(effects
				(font
					(size 1.27 1.27)
					(thickness 0.15)
				)
				(justify left bottom)
				(hide yes)
			)
		)
		(property "Manufacturer" ""
			(at 103.505 120.65 0)
			(effects
				(font
					(size 1.27 1.27)
					(thickness 0.15)
				)
				(justify left bottom)
				(hide yes)
			)
		)
		(property "Author" "Antmicro"
			(at 104.14 118.11 0)
			(effects
				(font
					(size 1.27 1.27)
					(thickness 0.15)
				)
				(justify left bottom)
				(hide yes)
			)
		)
		(property "License" "Apache-2.0"
			(at 104.14 115.57 0)
			(effects
				(font
					(size 1.27 1.27)
					(thickness 0.15)
				)
				(justify left bottom)
				(hide yes)
			)
		)
		(pin "1"
		)
		(instances
			(project "jetson-agx-thor-baseboard"
				(path ""
					(reference "TP2")
					(unit 1)
				)
			)
		)
	)
	(symbol
		(lib_id "antmicroCapacitors0402:C_100n_0402")
		(at 360.68 154.94 90)
		(mirror x)
		(unit 1)
		(exclude_from_sim no)
		(in_bom yes)
		(on_board yes)
		(dnp no)
		(fields_autoplaced yes)
		(property "Reference" "C106"
			(at 363.22 156.2163 90)
			(effects
				(font
					(size 1.27 1.27)
				)
				(justify right)
			)
		)
		(property "Value" "C_100n_0402"
			(at 370.84 175.26 0)
			(effects
				(font
					(size 1.27 1.27)
					(thickness 0.15)
				)
				(justify left bottom)
				(hide yes)
			)
		)
		(property "Footprint" "antmicro-footprints:C_0402_1005Metric"
			(at 373.38 175.26 0)
			(effects
				(font
					(size 1.27 1.27)
					(thickness 0.15)
				)
				(justify left bottom)
				(hide yes)
			)
		)
		(property "Datasheet" "https://www.murata.com/products/productdetail?partno=GRM155R61H104KE14%23"
			(at 375.92 175.26 0)
			(effects
				(font
					(size 1.27 1.27)
					(thickness 0.15)
				)
				(justify left bottom)
				(hide yes)
			)
		)
		(property "Description" "SMD Multilayer Ceramic Capacitor, 0.1 µF, 50 V, 0402 [1005 Metric], ± 10%, X5R, GRM Series"
			(at 360.68 154.94 0)
			(effects
				(font
					(size 1.27 1.27)
				)
				(hide yes)
			)
		)
		(property "Manufacturer" "Murata"
			(at 381 175.26 0)
			(effects
				(font
					(size 1.27 1.27)
					(thickness 0.15)
				)
				(justify left bottom)
				(hide yes)
			)
		)
		(property "MPN" "GRM155R61H104KE14D"
			(at 378.46 175.26 0)
			(effects
				(font
					(size 1.27 1.27)
					(thickness 0.15)
				)
				(justify left bottom)
				(hide yes)
			)
		)
		(property "Val" "100n"
			(at 363.22 158.7563 90)
			(effects
				(font
					(size 1.27 1.27)
					(thickness 0.15)
				)
				(justify right)
			)
		)
		(property "License" "Apache-2.0"
			(at 383.54 175.26 0)
			(effects
				(font
					(size 1.27 1.27)
					(thickness 0.15)
				)
				(justify left bottom)
				(hide yes)
			)
		)
		(property "Author" "Antmicro"
			(at 386.08 175.26 0)
			(effects
				(font
					(size 1.27 1.27)
					(thickness 0.15)
				)
				(justify left bottom)
				(hide yes)
			)
		)
		(property "Voltage" "50V"
			(at 388.62 175.26 0)
			(effects
				(font
					(size 1.27 1.27)
				)
				(justify left bottom)
				(hide yes)
			)
		)
		(property "Dielectric" "X5R"
			(at 391.16 175.26 0)
			(effects
				(font
					(size 1.27 1.27)
				)
				(justify left bottom)
				(hide yes)
			)
		)
		(pin "1"
		)
		(pin "2"
		)
		(instances
			(project "jetson-agx-thor-baseboard"
				(path ""
					(reference "C106")
					(unit 1)
				)
			)
		)
	)
	(symbol
		(lib_id "antmicropower:GND")
		(at 236.22 196.85 0)
		(unit 1)
		(exclude_from_sim no)
		(in_bom yes)
		(on_board yes)
		(dnp no)
		(property "Reference" "#PWR081"
			(at 236.22 203.2 0)
			(effects
				(font
					(size 1.27 1.27)
				)
				(justify left bottom)
				(hide yes)
			)
		)
		(property "Value" "GND"
			(at 236.22 200.66 0)
			(effects
				(font
					(size 1.27 1.27)
					(thickness 0.15)
				)
			)
		)
		(property "Footprint" ""
			(at 245.11 204.47 0)
			(effects
				(font
					(size 1.27 1.27)
					(thickness 0.15)
				)
				(justify left bottom)
				(hide yes)
			)
		)
		(property "Datasheet" ""
			(at 245.11 209.55 0)
			(effects
				(font
					(size 1.27 1.27)
					(thickness 0.15)
				)
				(justify left bottom)
				(hide yes)
			)
		)
		(property "Description" ""
			(at 236.22 196.85 0)
			(effects
				(font
					(size 1.27 1.27)
				)
				(hide yes)
			)
		)
		(property "Author" "Antmicro"
			(at 245.11 204.47 0)
			(effects
				(font
					(size 1.27 1.27)
					(thickness 0.15)
				)
				(justify left bottom)
				(hide yes)
			)
		)
		(property "License" "Apache-2.0"
			(at 245.11 207.01 0)
			(effects
				(font
					(size 1.27 1.27)
					(thickness 0.15)
				)
				(justify left bottom)
				(hide yes)
			)
		)
		(pin "1"
		)
		(instances
			(project "jetson-agx-thor-baseboard"
				(path ""
					(reference "#PWR081")
					(unit 1)
				)
			)
		)
	)
	(symbol
		(lib_id "antmicropower:+1V8")
		(at 17.78 40.64 0)
		(unit 1)
		(exclude_from_sim no)
		(in_bom yes)
		(on_board yes)
		(dnp no)
		(property "Reference" "#PWR0166"
			(at 33.02 43.18 0)
			(effects
				(font
					(size 1.27 1.27)
					(thickness 0.15)
				)
				(justify left bottom)
				(hide yes)
			)
		)
		(property "Value" "+1V15"
			(at 17.78 36.83 0)
			(effects
				(font
					(size 1.27 1.27)
					(thickness 0.15)
				)
			)
		)
		(property "Footprint" ""
			(at 33.02 48.26 0)
			(effects
				(font
					(size 1.27 1.27)
					(thickness 0.15)
				)
				(justify left bottom)
				(hide yes)
			)
		)
		(property "Datasheet" ""
			(at 33.02 50.8 0)
			(effects
				(font
					(size 1.27 1.27)
					(thickness 0.15)
				)
				(justify left bottom)
				(hide yes)
			)
		)
		(property "Description" ""
			(at 17.78 40.64 0)
			(effects
				(font
					(size 1.27 1.27)
				)
				(hide yes)
			)
		)
		(property "Author" "Antmicro"
			(at 33.02 45.72 0)
			(effects
				(font
					(size 1.27 1.27)
					(thickness 0.15)
				)
				(justify left bottom)
				(hide yes)
			)
		)
		(property "License" "Apache-2.0"
			(at 33.02 48.26 0)
			(effects
				(font
					(size 1.27 1.27)
					(thickness 0.15)
				)
				(justify left bottom)
				(hide yes)
			)
		)
		(pin "1"
		)
		(instances
			(project "jetson-agx-thor-baseboard"
				(path ""
					(reference "#PWR0166")
					(unit 1)
				)
			)
		)
	)
	(symbol
		(lib_id "antmicroCapacitorsmisc:C_22u_25V_0805")
		(at 350.52 154.94 90)
		(mirror x)
		(unit 1)
		(exclude_from_sim no)
		(in_bom yes)
		(on_board yes)
		(dnp no)
		(fields_autoplaced yes)
		(property "Reference" "C105"
			(at 353.06 156.2163 90)
			(effects
				(font
					(size 1.27 1.27)
				)
				(justify right)
			)
		)
		(property "Value" "C_22u_25V_0805"
			(at 360.68 175.26 0)
			(effects
				(font
					(size 1.27 1.27)
					(thickness 0.15)
				)
				(justify left bottom)
				(hide yes)
			)
		)
		(property "Footprint" "antmicro-footprints:C_0805_2012Metric"
			(at 363.22 175.26 0)
			(effects
				(font
					(size 1.27 1.27)
					(thickness 0.15)
				)
				(justify left bottom)
				(hide yes)
			)
		)
		(property "Datasheet" "https://product.samsungsem.com/mlcc/CL21A226MAYNNN.do"
			(at 365.76 175.26 0)
			(effects
				(font
					(size 1.27 1.27)
					(thickness 0.15)
				)
				(justify left bottom)
				(hide yes)
			)
		)
		(property "Description" "SMT Multilayer Ceramic Capacitor, 22uF, +/-20%, 25V, X5R, 0805 [2012 Metric]"
			(at 350.52 154.94 0)
			(effects
				(font
					(size 1.27 1.27)
				)
				(hide yes)
			)
		)
		(property "Manufacturer" "Samsung Electro-Mechanics"
			(at 370.84 175.26 0)
			(effects
				(font
					(size 1.27 1.27)
					(thickness 0.15)
				)
				(justify left bottom)
				(hide yes)
			)
		)
		(property "MPN" "CL21A226MAYNNNE"
			(at 368.3 175.26 0)
			(effects
				(font
					(size 1.27 1.27)
					(thickness 0.15)
				)
				(justify left bottom)
				(hide yes)
			)
		)
		(property "Val" "22u"
			(at 353.06 158.7563 90)
			(effects
				(font
					(size 1.27 1.27)
					(thickness 0.15)
				)
				(justify right)
			)
		)
		(property "License" "Apache-2.0"
			(at 373.38 175.26 0)
			(effects
				(font
					(size 1.27 1.27)
					(thickness 0.15)
				)
				(justify left bottom)
				(hide yes)
			)
		)
		(property "Author" "Antmicro"
			(at 375.92 175.26 0)
			(effects
				(font
					(size 1.27 1.27)
					(thickness 0.15)
				)
				(justify left bottom)
				(hide yes)
			)
		)
		(property "Voltage" "25V"
			(at 378.46 175.26 0)
			(effects
				(font
					(size 1.27 1.27)
				)
				(justify left bottom)
				(hide yes)
			)
		)
		(property "Dielectric" "X5R"
			(at 381 175.26 0)
			(effects
				(font
					(size 1.27 1.27)
				)
				(justify left bottom)
				(hide yes)
			)
		)
		(property "Public" "False"
			(at 383.54 175.26 0)
			(effects
				(font
					(size 1.27 1.27)
				)
				(justify left bottom)
				(hide yes)
			)
		)
		(pin "1"
		)
		(pin "2"
		)
		(instances
			(project "jetson-agx-thor-baseboard"
				(path ""
					(reference "C105")
					(unit 1)
				)
			)
		)
	)
	(symbol
		(lib_id "antmicroCapacitors0402:C_100n_0402")
		(at 68.58 48.26 90)
		(unit 1)
		(exclude_from_sim no)
		(in_bom yes)
		(on_board yes)
		(dnp no)
		(fields_autoplaced yes)
		(property "Reference" "C92"
			(at 71.12 44.4436 90)
			(effects
				(font
					(size 1.27 1.27)
					(thickness 0.15)
				)
				(justify right)
			)
		)
		(property "Value" "C_100n_0402"
			(at 91.44 33.02 0)
			(effects
				(font
					(size 1.27 1.27)
					(thickness 0.15)
				)
				(justify left bottom)
				(hide yes)
			)
		)
		(property "Footprint" "antmicro-footprints:C_0402_1005Metric"
			(at 93.98 33.02 0)
			(effects
				(font
					(size 1.27 1.27)
					(thickness 0.15)
				)
				(justify left bottom)
				(hide yes)
			)
		)
		(property "Datasheet" "https://www.murata.com/products/productdetail?partno=GRM155R61H104KE14%23"
			(at 96.52 33.02 0)
			(effects
				(font
					(size 1.27 1.27)
					(thickness 0.15)
				)
				(justify left bottom)
				(hide yes)
			)
		)
		(property "Description" "SMD Multilayer Ceramic Capacitor, 0.1 µF, 50 V, 0402 [1005 Metric], ± 10%, X5R, GRM Series"
			(at 68.58 48.26 0)
			(effects
				(font
					(size 1.27 1.27)
				)
				(hide yes)
			)
		)
		(property "MPN" "GRM155R61H104KE14D"
			(at 99.06 33.02 0)
			(effects
				(font
					(size 1.27 1.27)
					(thickness 0.15)
				)
				(justify left bottom)
				(hide yes)
			)
		)
		(property "Val" "100n"
			(at 71.12 46.9836 90)
			(effects
				(font
					(size 1.27 1.27)
					(thickness 0.15)
				)
				(justify right)
			)
		)
		(property "Voltage" "50V"
			(at 78.74 33.02 0)
			(effects
				(font
					(size 1.27 1.27)
					(thickness 0.15)
				)
				(justify left bottom)
				(hide yes)
			)
		)
		(property "Dielectric" "X5R"
			(at 81.28 33.02 0)
			(effects
				(font
					(size 1.27 1.27)
					(thickness 0.15)
				)
				(justify left bottom)
				(hide yes)
			)
		)
		(property "Manufacturer" "Murata"
			(at 83.82 33.02 0)
			(effects
				(font
					(size 1.27 1.27)
					(thickness 0.15)
				)
				(justify left bottom)
				(hide yes)
			)
		)
		(property "License" "Apache-2.0"
			(at 86.36 33.02 0)
			(effects
				(font
					(size 1.27 1.27)
					(thickness 0.15)
				)
				(justify left bottom)
				(hide yes)
			)
		)
		(property "Author" "Antmicro"
			(at 88.9 33.02 0)
			(effects
				(font
					(size 1.27 1.27)
					(thickness 0.15)
				)
				(justify left bottom)
				(hide yes)
			)
		)
		(pin "1"
		)
		(pin "2"
		)
		(instances
			(project "jetson-agx-thor-baseboard"
				(path ""
					(reference "C92")
					(unit 1)
				)
			)
		)
	)
	(symbol
		(lib_id "antmicroTestPoints:TP_0.75mm_SMD")
		(at 114.3 99.06 180)
		(unit 1)
		(exclude_from_sim no)
		(in_bom no)
		(on_board yes)
		(dnp no)
		(property "Reference" "TP65"
			(at 110.236 98.298 0)
			(effects
				(font
					(size 1.27 1.27)
				)
				(justify left bottom)
			)
		)
		(property "Value" "TP_0.75mm_SMD"
			(at 104.14 95.25 0)
			(effects
				(font
					(size 1.27 1.27)
					(thickness 0.15)
				)
				(justify left bottom)
				(hide yes)
			)
		)
		(property "Footprint" "antmicro-footprints:TP_SMD_0.75mm"
			(at 104.14 92.71 0)
			(effects
				(font
					(size 1.27 1.27)
					(thickness 0.15)
				)
				(justify left bottom)
				(hide yes)
			)
		)
		(property "Datasheet" ""
			(at 96.52 86.36 0)
			(effects
				(font
					(size 1.27 1.27)
					(thickness 0.15)
				)
				(justify left bottom)
				(hide yes)
			)
		)
		(property "Description" "SMT test point"
			(at 114.3 99.06 0)
			(effects
				(font
					(size 1.27 1.27)
				)
				(hide yes)
			)
		)
		(property "MPN" ""
			(at 103.505 87.63 0)
			(effects
				(font
					(size 1.27 1.27)
					(thickness 0.15)
				)
				(justify left bottom)
				(hide yes)
			)
		)
		(property "Manufacturer" ""
			(at 103.505 92.71 0)
			(effects
				(font
					(size 1.27 1.27)
					(thickness 0.15)
				)
				(justify left bottom)
				(hide yes)
			)
		)
		(property "Author" "Antmicro"
			(at 104.14 90.17 0)
			(effects
				(font
					(size 1.27 1.27)
					(thickness 0.15)
				)
				(justify left bottom)
				(hide yes)
			)
		)
		(property "License" "Apache-2.0"
			(at 104.14 87.63 0)
			(effects
				(font
					(size 1.27 1.27)
					(thickness 0.15)
				)
				(justify left bottom)
				(hide yes)
			)
		)
		(pin "1"
		)
		(instances
			(project "jetson-agx-thor-baseboard"
				(path ""
					(reference "TP65")
					(unit 1)
				)
			)
		)
	)
	(symbol
		(lib_id "antmicroResistors0402:R_200k_0402")
		(at 27.94 196.85 90)
		(unit 1)
		(exclude_from_sim no)
		(in_bom no)
		(on_board yes)
		(dnp yes)
		(property "Reference" "R78"
			(at 28.956 193.04 90)
			(effects
				(font
					(size 1.27 1.27)
					(thickness 0.15)
				)
				(justify right)
			)
		)
		(property "Value" "R_200k_0402"
			(at 40.64 176.53 0)
			(effects
				(font
					(size 1.27 1.27)
					(thickness 0.15)
				)
				(justify left bottom)
				(hide yes)
			)
		)
		(property "Footprint" "antmicro-footprints:R_0402_1005Metric"
			(at 43.18 176.53 0)
			(effects
				(font
					(size 1.27 1.27)
					(thickness 0.15)
				)
				(justify left bottom)
				(hide yes)
			)
		)
		(property "Datasheet" "https://www.bourns.com/docs/product-datasheets/cr.pdf"
			(at 45.72 176.53 0)
			(effects
				(font
					(size 1.27 1.27)
					(thickness 0.15)
				)
				(justify left bottom)
				(hide yes)
			)
		)
		(property "Description" "SMD Chip Resistor, 200 kohm, ± 1%, 62.5 mW, 0402 [1005 Metric], Thick Film, General Purpose"
			(at 27.94 196.85 0)
			(effects
				(font
					(size 1.27 1.27)
				)
				(hide yes)
			)
		)
		(property "MPN" "CR0402-FX-2003GLF"
			(at 48.26 176.53 0)
			(effects
				(font
					(size 1.27 1.27)
					(thickness 0.15)
				)
				(justify left bottom)
				(hide yes)
			)
		)
		(property "Manufacturer" "Bourns"
			(at 50.8 176.53 0)
			(effects
				(font
					(size 1.27 1.27)
					(thickness 0.15)
				)
				(justify left bottom)
				(hide yes)
			)
		)
		(property "License" "Apache-2.0"
			(at 53.34 176.53 0)
			(effects
				(font
					(size 1.27 1.27)
					(thickness 0.15)
				)
				(justify left bottom)
				(hide yes)
			)
		)
		(property "Author" "Antmicro"
			(at 55.88 176.53 0)
			(effects
				(font
					(size 1.27 1.27)
					(thickness 0.15)
				)
				(justify left bottom)
				(hide yes)
			)
		)
		(property "Val" "200k"
			(at 28.956 195.58 90)
			(effects
				(font
					(size 1.27 1.27)
					(thickness 0.15)
				)
				(justify right)
			)
		)
		(property "Tolerance" "1%"
			(at 38.1 176.53 0)
			(effects
				(font
					(size 1.27 1.27)
				)
				(justify left bottom)
				(hide yes)
			)
		)
		(pin "1"
		)
		(pin "2"
		)
		(instances
			(project "jetson-agx-thor-baseboard"
				(path ""
					(reference "R78")
					(unit 1)
				)
			)
		)
	)
	(symbol
		(lib_id "antmicroResistors0402:R_10k_0402")
		(at 107.95 165.1 270)
		(unit 1)
		(exclude_from_sim no)
		(in_bom yes)
		(on_board yes)
		(dnp no)
		(property "Reference" "R86"
			(at 109.22 166.116 90)
			(effects
				(font
					(size 1.27 1.27)
					(thickness 0.15)
				)
				(justify left)
			)
		)
		(property "Value" "R_10k_0402"
			(at 95.25 185.42 0)
			(effects
				(font
					(size 1.27 1.27)
					(thickness 0.15)
				)
				(justify left bottom)
				(hide yes)
			)
		)
		(property "Footprint" "antmicro-footprints:R_0402_1005Metric"
			(at 92.71 185.42 0)
			(effects
				(font
					(size 1.27 1.27)
					(thickness 0.15)
				)
				(justify left bottom)
				(hide yes)
			)
		)
		(property "Datasheet" "https://www.bourns.com/docs/product-datasheets/cr.pdf"
			(at 90.17 185.42 0)
			(effects
				(font
					(size 1.27 1.27)
					(thickness 0.15)
				)
				(justify left bottom)
				(hide yes)
			)
		)
		(property "Description" "SMD Chip Resistor, 10 kohm, ± 1%, 62.5 mW, 0402 [1005 Metric], Thick Film, General Purpose"
			(at 107.95 165.1 0)
			(effects
				(font
					(size 1.27 1.27)
				)
				(hide yes)
			)
		)
		(property "MPN" "CR0402-FX-1002GLF"
			(at 87.63 185.42 0)
			(effects
				(font
					(size 1.27 1.27)
					(thickness 0.15)
				)
				(justify left bottom)
				(hide yes)
			)
		)
		(property "Manufacturer" "Bourns"
			(at 85.09 185.42 0)
			(effects
				(font
					(size 1.27 1.27)
					(thickness 0.15)
				)
				(justify left bottom)
				(hide yes)
			)
		)
		(property "License" "Apache-2.0"
			(at 82.55 185.42 0)
			(effects
				(font
					(size 1.27 1.27)
					(thickness 0.15)
				)
				(justify left bottom)
				(hide yes)
			)
		)
		(property "Author" "Antmicro"
			(at 80.01 185.42 0)
			(effects
				(font
					(size 1.27 1.27)
					(thickness 0.15)
				)
				(justify left bottom)
				(hide yes)
			)
		)
		(property "Val" "10k"
			(at 109.22 168.656 90)
			(effects
				(font
					(size 1.27 1.27)
					(thickness 0.15)
				)
				(justify left)
			)
		)
		(property "Tolerance" "1%"
			(at 97.79 185.42 0)
			(effects
				(font
					(size 1.27 1.27)
				)
				(justify left bottom)
				(hide yes)
			)
		)
		(pin "2"
		)
		(pin "1"
		)
		(instances
			(project "jetson-agx-thor-baseboard"
				(path ""
					(reference "R86")
					(unit 1)
				)
			)
		)
	)
	(symbol
		(lib_id "antmicroDiodesRectifiersSingle:RB521S30T1G")
		(at 172.72 255.27 180)
		(unit 1)
		(exclude_from_sim no)
		(in_bom yes)
		(on_board yes)
		(dnp no)
		(property "Reference" "D58"
			(at 170.688 248.92 0)
			(effects
				(font
					(size 1.27 1.27)
				)
			)
		)
		(property "Value" "RB521S30T1G"
			(at 149.86 240.03 0)
			(effects
				(font
					(size 1.27 1.27)
					(thickness 0.15)
				)
				(justify left bottom)
				(hide yes)
			)
		)
		(property "Footprint" "antmicro-footprints:SOD-523"
			(at 149.86 245.11 0)
			(effects
				(font
					(size 1.27 1.27)
					(thickness 0.15)
				)
				(justify left bottom)
				(hide yes)
			)
		)
		(property "Datasheet" "https://www.onsemi.com/pdf/datasheet/rb521s30t1-d.pdf"
			(at 149.86 242.57 0)
			(effects
				(font
					(size 1.27 1.27)
					(thickness 0.15)
				)
				(justify left bottom)
				(hide yes)
			)
		)
		(property "Description" "Small Signal Schottky Diode, Single, 30 V, 200 mA, 500 mV, 1 A, 125 °C"
			(at 172.72 255.27 0)
			(effects
				(font
					(size 1.27 1.27)
				)
				(hide yes)
			)
		)
		(property "MPN" "RB521S30T1G"
			(at 170.688 251.46 0)
			(effects
				(font
					(size 1.27 1.27)
					(thickness 0.15)
				)
			)
		)
		(property "Manufacturer" "ON Semiconductor"
			(at 149.86 237.49 0)
			(effects
				(font
					(size 1.27 1.27)
					(thickness 0.15)
				)
				(justify left bottom)
				(hide yes)
			)
		)
		(property "Author" "Antmicro"
			(at 149.86 234.95 0)
			(effects
				(font
					(size 1.27 1.27)
					(thickness 0.15)
				)
				(justify left bottom)
				(hide yes)
			)
		)
		(property "License" "Apache-2.0"
			(at 149.86 232.41 0)
			(effects
				(font
					(size 1.27 1.27)
					(thickness 0.15)
				)
				(justify left bottom)
				(hide yes)
			)
		)
		(pin "1"
		)
		(pin "2"
		)
		(instances
			(project "jetson-agx-thor-baseboard"
				(path ""
					(reference "D58")
					(unit 1)
				)
			)
		)
	)
	(symbol
		(lib_id "antmicroResistors0402:R_2R2_0402")
		(at 176.53 231.14 0)
		(unit 1)
		(exclude_from_sim no)
		(in_bom yes)
		(on_board yes)
		(dnp no)
		(property "Reference" "R330"
			(at 178.816 228.854 0)
			(effects
				(font
					(size 1.27 1.27)
					(thickness 0.15)
				)
			)
		)
		(property "Value" "R_2R2_0402"
			(at 196.85 243.84 0)
			(effects
				(font
					(size 1.27 1.27)
					(thickness 0.15)
				)
				(justify left bottom)
				(hide yes)
			)
		)
		(property "Footprint" "antmicro-footprints:R_0402_1005Metric"
			(at 196.85 246.38 0)
			(effects
				(font
					(size 1.27 1.27)
					(thickness 0.15)
				)
				(justify left bottom)
				(hide yes)
			)
		)
		(property "Datasheet" "https://www.bourns.com/docs/product-datasheets/cr.pdf"
			(at 196.85 248.92 0)
			(effects
				(font
					(size 1.27 1.27)
					(thickness 0.15)
				)
				(justify left bottom)
				(hide yes)
			)
		)
		(property "Description" "SMD Chip Resistor, 2.2 ohm, ± 1%, 62.5 mW, 0402 [1005 Metric], Thick Film, General Purpose"
			(at 196.85 261.62 0)
			(effects
				(font
					(size 1.27 1.27)
				)
				(justify left bottom)
				(hide yes)
			)
		)
		(property "MPN" "CR0402-FX-2R20GLF"
			(at 196.85 251.46 0)
			(effects
				(font
					(size 1.27 1.27)
					(thickness 0.15)
				)
				(justify left bottom)
				(hide yes)
			)
		)
		(property "Manufacturer" "Bourns"
			(at 196.85 254 0)
			(effects
				(font
					(size 1.27 1.27)
					(thickness 0.15)
				)
				(justify left bottom)
				(hide yes)
			)
		)
		(property "License" "Apache-2.0"
			(at 196.85 256.54 0)
			(effects
				(font
					(size 1.27 1.27)
					(thickness 0.15)
				)
				(justify left bottom)
				(hide yes)
			)
		)
		(property "Author" "Antmicro"
			(at 196.85 259.08 0)
			(effects
				(font
					(size 1.27 1.27)
					(thickness 0.15)
				)
				(justify left bottom)
				(hide yes)
			)
		)
		(property "Val" "2R2"
			(at 178.816 233.426 0)
			(effects
				(font
					(size 1.27 1.27)
					(thickness 0.15)
				)
			)
		)
		(property "Tolerance" "1%"
			(at 196.85 241.3 0)
			(effects
				(font
					(size 1.27 1.27)
				)
				(justify left bottom)
				(hide yes)
			)
		)
		(pin "2"
		)
		(pin "1"
		)
		(instances
			(project "jetson-agx-thor-baseboard"
				(path ""
					(reference "R330")
					(unit 1)
				)
			)
		)
	)
	(symbol
		(lib_id "antmicroResistors0402:R_100k_0402")
		(at 198.12 195.58 270)
		(mirror x)
		(unit 1)
		(exclude_from_sim no)
		(in_bom yes)
		(on_board yes)
		(dnp no)
		(property "Reference" "R194"
			(at 196.85 191.77 90)
			(effects
				(font
					(size 1.27 1.27)
					(thickness 0.15)
				)
				(justify right)
			)
		)
		(property "Value" "R_100k_0402"
			(at 185.42 175.26 0)
			(effects
				(font
					(size 1.27 1.27)
					(thickness 0.15)
				)
				(justify left bottom)
				(hide yes)
			)
		)
		(property "Footprint" "antmicro-footprints:R_0402_1005Metric"
			(at 182.88 175.26 0)
			(effects
				(font
					(size 1.27 1.27)
					(thickness 0.15)
				)
				(justify left bottom)
				(hide yes)
			)
		)
		(property "Datasheet" "https://www.bourns.com/docs/product-datasheets/cr.pdf"
			(at 180.34 175.26 0)
			(effects
				(font
					(size 1.27 1.27)
					(thickness 0.15)
				)
				(justify left bottom)
				(hide yes)
			)
		)
		(property "Description" "SMD Chip Resistor, 100 kohm, ± 1%, 62.5 mW, 0402 [1005 Metric], Thick Film, General Purpose"
			(at 167.64 175.26 0)
			(effects
				(font
					(size 1.27 1.27)
				)
				(justify left bottom)
				(hide yes)
			)
		)
		(property "MPN" "CR0402-FX-1003GLF"
			(at 177.8 175.26 0)
			(effects
				(font
					(size 1.27 1.27)
					(thickness 0.15)
				)
				(justify left bottom)
				(hide yes)
			)
		)
		(property "Manufacturer" "Bourns"
			(at 175.26 175.26 0)
			(effects
				(font
					(size 1.27 1.27)
					(thickness 0.15)
				)
				(justify left bottom)
				(hide yes)
			)
		)
		(property "License" "Apache-2.0"
			(at 172.72 175.26 0)
			(effects
				(font
					(size 1.27 1.27)
					(thickness 0.15)
				)
				(justify left bottom)
				(hide yes)
			)
		)
		(property "Author" "Antmicro"
			(at 170.18 175.26 0)
			(effects
				(font
					(size 1.27 1.27)
					(thickness 0.15)
				)
				(justify left bottom)
				(hide yes)
			)
		)
		(property "Val" "100k"
			(at 196.85 194.31 90)
			(effects
				(font
					(size 1.27 1.27)
					(thickness 0.15)
				)
				(justify right)
			)
		)
		(property "Tolerance" "1%"
			(at 187.96 175.26 0)
			(effects
				(font
					(size 1.27 1.27)
				)
				(justify left bottom)
				(hide yes)
			)
		)
		(pin "2"
		)
		(pin "1"
		)
		(instances
			(project "jetson-agx-thor-baseboard"
				(path ""
					(reference "R194")
					(unit 1)
				)
			)
		)
	)
	(symbol
		(lib_id "antmicropower:GND")
		(at 374.65 39.37 0)
		(unit 1)
		(exclude_from_sim no)
		(in_bom yes)
		(on_board yes)
		(dnp no)
		(property "Reference" "#PWR0175"
			(at 374.65 45.72 0)
			(effects
				(font
					(size 1.27 1.27)
				)
				(justify left bottom)
				(hide yes)
			)
		)
		(property "Value" "GND"
			(at 374.65 43.18 0)
			(effects
				(font
					(size 1.27 1.27)
					(thickness 0.15)
				)
			)
		)
		(property "Footprint" ""
			(at 383.54 46.99 0)
			(effects
				(font
					(size 1.27 1.27)
					(thickness 0.15)
				)
				(justify left bottom)
				(hide yes)
			)
		)
		(property "Datasheet" ""
			(at 383.54 52.07 0)
			(effects
				(font
					(size 1.27 1.27)
					(thickness 0.15)
				)
				(justify left bottom)
				(hide yes)
			)
		)
		(property "Description" ""
			(at 374.65 39.37 0)
			(effects
				(font
					(size 1.27 1.27)
				)
				(hide yes)
			)
		)
		(property "Author" "Antmicro"
			(at 383.54 46.99 0)
			(effects
				(font
					(size 1.27 1.27)
					(thickness 0.15)
				)
				(justify left bottom)
				(hide yes)
			)
		)
		(property "License" "Apache-2.0"
			(at 383.54 49.53 0)
			(effects
				(font
					(size 1.27 1.27)
					(thickness 0.15)
				)
				(justify left bottom)
				(hide yes)
			)
		)
		(pin "1"
		)
		(instances
			(project "jetson-agx-thor-baseboard"
				(path ""
					(reference "#PWR0175")
					(unit 1)
				)
			)
		)
	)
	(symbol
		(lib_id "antmicroResistors0402:R_10k_0402")
		(at 226.06 260.35 270)
		(unit 1)
		(exclude_from_sim no)
		(in_bom yes)
		(on_board yes)
		(dnp no)
		(property "Reference" "R335"
			(at 232.41 261.62 90)
			(effects
				(font
					(size 1.27 1.27)
					(thickness 0.15)
				)
				(justify right)
			)
		)
		(property "Value" "R_10k_0402"
			(at 213.36 280.67 0)
			(effects
				(font
					(size 1.27 1.27)
					(thickness 0.15)
				)
				(justify left bottom)
				(hide yes)
			)
		)
		(property "Footprint" "antmicro-footprints:R_0402_1005Metric"
			(at 210.82 280.67 0)
			(effects
				(font
					(size 1.27 1.27)
					(thickness 0.15)
				)
				(justify left bottom)
				(hide yes)
			)
		)
		(property "Datasheet" "https://www.bourns.com/docs/product-datasheets/cr.pdf"
			(at 208.28 280.67 0)
			(effects
				(font
					(size 1.27 1.27)
					(thickness 0.15)
				)
				(justify left bottom)
				(hide yes)
			)
		)
		(property "Description" "SMD Chip Resistor, 10 kohm, ± 1%, 62.5 mW, 0402 [1005 Metric], Thick Film, General Purpose"
			(at 226.06 260.35 0)
			(effects
				(font
					(size 1.27 1.27)
				)
				(hide yes)
			)
		)
		(property "MPN" "CR0402-FX-1002GLF"
			(at 205.74 280.67 0)
			(effects
				(font
					(size 1.27 1.27)
					(thickness 0.15)
				)
				(justify left bottom)
				(hide yes)
			)
		)
		(property "Manufacturer" "Bourns"
			(at 203.2 280.67 0)
			(effects
				(font
					(size 1.27 1.27)
					(thickness 0.15)
				)
				(justify left bottom)
				(hide yes)
			)
		)
		(property "License" "Apache-2.0"
			(at 200.66 280.67 0)
			(effects
				(font
					(size 1.27 1.27)
					(thickness 0.15)
				)
				(justify left bottom)
				(hide yes)
			)
		)
		(property "Author" "Antmicro"
			(at 198.12 280.67 0)
			(effects
				(font
					(size 1.27 1.27)
					(thickness 0.15)
				)
				(justify left bottom)
				(hide yes)
			)
		)
		(property "Val" "10k"
			(at 231.14 264.16 90)
			(effects
				(font
					(size 1.27 1.27)
					(thickness 0.15)
				)
				(justify right)
			)
		)
		(property "Tolerance" "1%"
			(at 215.9 280.67 0)
			(effects
				(font
					(size 1.27 1.27)
				)
				(justify left bottom)
				(hide yes)
			)
		)
		(pin "2"
		)
		(pin "1"
		)
		(instances
			(project "jetson-agx-thor-baseboard"
				(path ""
					(reference "R335")
					(unit 1)
				)
			)
		)
	)
	(symbol
		(lib_id "antmicroCapacitors0402:C_100n_0402")
		(at 285.75 88.9 180)
		(unit 1)
		(exclude_from_sim no)
		(in_bom yes)
		(on_board yes)
		(dnp no)
		(property "Reference" "C101"
			(at 289.56 86.868 0)
			(effects
				(font
					(size 1.27 1.27)
				)
				(justify left bottom)
			)
		)
		(property "Value" "C_100n_0402"
			(at 265.43 78.74 0)
			(effects
				(font
					(size 1.27 1.27)
					(thickness 0.15)
				)
				(justify left bottom)
				(hide yes)
			)
		)
		(property "Footprint" "antmicro-footprints:C_0402_1005Metric"
			(at 265.43 76.2 0)
			(effects
				(font
					(size 1.27 1.27)
					(thickness 0.15)
				)
				(justify left bottom)
				(hide yes)
			)
		)
		(property "Datasheet" "https://www.murata.com/products/productdetail?partno=GRM155R61H104KE14%23"
			(at 265.43 73.66 0)
			(effects
				(font
					(size 1.27 1.27)
					(thickness 0.15)
				)
				(justify left bottom)
				(hide yes)
			)
		)
		(property "Description" "SMD Multilayer Ceramic Capacitor, 0.1 µF, 50 V, 0402 [1005 Metric], ± 10%, X5R, GRM Series"
			(at 285.75 88.9 0)
			(effects
				(font
					(size 1.27 1.27)
				)
				(hide yes)
			)
		)
		(property "Manufacturer" "Murata"
			(at 265.43 68.58 0)
			(effects
				(font
					(size 1.27 1.27)
					(thickness 0.15)
				)
				(justify left bottom)
				(hide yes)
			)
		)
		(property "MPN" "GRM155R61H104KE14D"
			(at 265.43 71.12 0)
			(effects
				(font
					(size 1.27 1.27)
					(thickness 0.15)
				)
				(justify left bottom)
				(hide yes)
			)
		)
		(property "Val" "100n"
			(at 281.94 89.535 0)
			(effects
				(font
					(size 1.27 1.27)
					(thickness 0.15)
				)
				(justify left bottom)
			)
		)
		(property "License" "Apache-2.0"
			(at 265.43 66.04 0)
			(effects
				(font
					(size 1.27 1.27)
					(thickness 0.15)
				)
				(justify left bottom)
				(hide yes)
			)
		)
		(property "Author" "Antmicro"
			(at 265.43 63.5 0)
			(effects
				(font
					(size 1.27 1.27)
					(thickness 0.15)
				)
				(justify left bottom)
				(hide yes)
			)
		)
		(property "Voltage" "50V"
			(at 265.43 60.96 0)
			(effects
				(font
					(size 1.27 1.27)
				)
				(justify left bottom)
				(hide yes)
			)
		)
		(property "Dielectric" "X5R"
			(at 265.43 58.42 0)
			(effects
				(font
					(size 1.27 1.27)
				)
				(justify left bottom)
				(hide yes)
			)
		)
		(pin "1"
		)
		(pin "2"
		)
		(instances
			(project "jetson-agx-thor-baseboard"
				(path ""
					(reference "C101")
					(unit 1)
				)
			)
		)
	)
	(symbol
		(lib_id "antmicroCapacitors0402:C_100n_0402")
		(at 308.61 22.86 90)
		(mirror x)
		(unit 1)
		(exclude_from_sim no)
		(in_bom yes)
		(on_board yes)
		(dnp no)
		(fields_autoplaced yes)
		(property "Reference" "C77"
			(at 311.15 24.1363 90)
			(effects
				(font
					(size 1.27 1.27)
				)
				(justify right)
			)
		)
		(property "Value" "C_100n_0402"
			(at 318.77 43.18 0)
			(effects
				(font
					(size 1.27 1.27)
					(thickness 0.15)
				)
				(justify left bottom)
				(hide yes)
			)
		)
		(property "Footprint" "antmicro-footprints:C_0402_1005Metric"
			(at 321.31 43.18 0)
			(effects
				(font
					(size 1.27 1.27)
					(thickness 0.15)
				)
				(justify left bottom)
				(hide yes)
			)
		)
		(property "Datasheet" "https://www.murata.com/products/productdetail?partno=GRM155R61H104KE14%23"
			(at 323.85 43.18 0)
			(effects
				(font
					(size 1.27 1.27)
					(thickness 0.15)
				)
				(justify left bottom)
				(hide yes)
			)
		)
		(property "Description" "SMD Multilayer Ceramic Capacitor, 0.1 µF, 50 V, 0402 [1005 Metric], ± 10%, X5R, GRM Series"
			(at 308.61 22.86 0)
			(effects
				(font
					(size 1.27 1.27)
				)
				(hide yes)
			)
		)
		(property "Manufacturer" "Murata"
			(at 328.93 43.18 0)
			(effects
				(font
					(size 1.27 1.27)
					(thickness 0.15)
				)
				(justify left bottom)
				(hide yes)
			)
		)
		(property "MPN" "GRM155R61H104KE14D"
			(at 326.39 43.18 0)
			(effects
				(font
					(size 1.27 1.27)
					(thickness 0.15)
				)
				(justify left bottom)
				(hide yes)
			)
		)
		(property "Val" "100n"
			(at 311.15 26.6763 90)
			(effects
				(font
					(size 1.27 1.27)
					(thickness 0.15)
				)
				(justify right)
			)
		)
		(property "License" "Apache-2.0"
			(at 331.47 43.18 0)
			(effects
				(font
					(size 1.27 1.27)
					(thickness 0.15)
				)
				(justify left bottom)
				(hide yes)
			)
		)
		(property "Author" "Antmicro"
			(at 334.01 43.18 0)
			(effects
				(font
					(size 1.27 1.27)
					(thickness 0.15)
				)
				(justify left bottom)
				(hide yes)
			)
		)
		(property "Voltage" "50V"
			(at 336.55 43.18 0)
			(effects
				(font
					(size 1.27 1.27)
				)
				(justify left bottom)
				(hide yes)
			)
		)
		(property "Dielectric" "X5R"
			(at 339.09 43.18 0)
			(effects
				(font
					(size 1.27 1.27)
				)
				(justify left bottom)
				(hide yes)
			)
		)
		(pin "1"
		)
		(pin "2"
		)
		(instances
			(project "jetson-agx-thor-baseboard"
				(path ""
					(reference "C77")
					(unit 1)
				)
			)
		)
	)
	(symbol
		(lib_id "antmicropower:+5V")
		(at 308.61 20.32 0)
		(unit 1)
		(exclude_from_sim no)
		(in_bom yes)
		(on_board yes)
		(dnp no)
		(property "Reference" "#PWR0169"
			(at 308.61 24.13 0)
			(effects
				(font
					(size 1.27 1.27)
				)
				(justify left bottom)
				(hide yes)
			)
		)
		(property "Value" "+5V"
			(at 306.705 17.145 0)
			(effects
				(font
					(size 1.27 1.27)
					(thickness 0.15)
				)
				(justify left bottom)
			)
		)
		(property "Footprint" ""
			(at 323.85 27.94 0)
			(effects
				(font
					(size 1.27 1.27)
					(thickness 0.15)
				)
				(justify left bottom)
				(hide yes)
			)
		)
		(property "Datasheet" ""
			(at 323.85 30.48 0)
			(effects
				(font
					(size 1.27 1.27)
					(thickness 0.15)
				)
				(justify left bottom)
				(hide yes)
			)
		)
		(property "Description" ""
			(at 308.61 20.32 0)
			(effects
				(font
					(size 1.27 1.27)
				)
				(hide yes)
			)
		)
		(property "Author" "Antmicro"
			(at 323.85 27.94 0)
			(effects
				(font
					(size 1.27 1.27)
					(thickness 0.15)
				)
				(justify left bottom)
				(hide yes)
			)
		)
		(property "License" "Apache-2.0"
			(at 323.85 30.48 0)
			(effects
				(font
					(size 1.27 1.27)
					(thickness 0.15)
				)
				(justify left bottom)
				(hide yes)
			)
		)
		(pin "1"
		)
		(instances
			(project "jetson-agx-thor-baseboard"
				(path ""
					(reference "#PWR0169")
					(unit 1)
				)
			)
		)
	)
	(symbol
		(lib_id "antmicroTestPoints:TP_0.75mm_SMD")
		(at 114.3 129.54 180)
		(unit 1)
		(exclude_from_sim no)
		(in_bom no)
		(on_board yes)
		(dnp no)
		(property "Reference" "TP40"
			(at 110.236 128.778 0)
			(effects
				(font
					(size 1.27 1.27)
				)
				(justify left bottom)
			)
		)
		(property "Value" "TP_0.75mm_SMD"
			(at 104.14 125.73 0)
			(effects
				(font
					(size 1.27 1.27)
					(thickness 0.15)
				)
				(justify left bottom)
				(hide yes)
			)
		)
		(property "Footprint" "antmicro-footprints:TP_SMD_0.75mm"
			(at 104.14 123.19 0)
			(effects
				(font
					(size 1.27 1.27)
					(thickness 0.15)
				)
				(justify left bottom)
				(hide yes)
			)
		)
		(property "Datasheet" ""
			(at 96.52 116.84 0)
			(effects
				(font
					(size 1.27 1.27)
					(thickness 0.15)
				)
				(justify left bottom)
				(hide yes)
			)
		)
		(property "Description" "SMT test point"
			(at 114.3 129.54 0)
			(effects
				(font
					(size 1.27 1.27)
				)
				(hide yes)
			)
		)
		(property "MPN" ""
			(at 103.505 118.11 0)
			(effects
				(font
					(size 1.27 1.27)
					(thickness 0.15)
				)
				(justify left bottom)
				(hide yes)
			)
		)
		(property "Manufacturer" ""
			(at 103.505 123.19 0)
			(effects
				(font
					(size 1.27 1.27)
					(thickness 0.15)
				)
				(justify left bottom)
				(hide yes)
			)
		)
		(property "Author" "Antmicro"
			(at 104.14 120.65 0)
			(effects
				(font
					(size 1.27 1.27)
					(thickness 0.15)
				)
				(justify left bottom)
				(hide yes)
			)
		)
		(property "License" "Apache-2.0"
			(at 104.14 118.11 0)
			(effects
				(font
					(size 1.27 1.27)
					(thickness 0.15)
				)
				(justify left bottom)
				(hide yes)
			)
		)
		(pin "1"
		)
		(instances
			(project "jetson-agx-thor-baseboard"
				(path ""
					(reference "TP40")
					(unit 1)
				)
			)
		)
	)
	(symbol
		(lib_id "antmicroCapacitors0402:C_100n_0402")
		(at 99.06 82.55 0)
		(mirror x)
		(unit 1)
		(exclude_from_sim no)
		(in_bom yes)
		(on_board yes)
		(dnp no)
		(property "Reference" "C256"
			(at 105.41 81.28 0)
			(effects
				(font
					(size 1.27 1.27)
				)
			)
		)
		(property "Value" "C_100n_0402"
			(at 119.38 72.39 0)
			(effects
				(font
					(size 1.27 1.27)
					(thickness 0.15)
				)
				(justify left bottom)
				(hide yes)
			)
		)
		(property "Footprint" "antmicro-footprints:C_0402_1005Metric"
			(at 119.38 69.85 0)
			(effects
				(font
					(size 1.27 1.27)
					(thickness 0.15)
				)
				(justify left bottom)
				(hide yes)
			)
		)
		(property "Datasheet" "https://www.murata.com/products/productdetail?partno=GRM155R61H104KE14%23"
			(at 119.38 67.31 0)
			(effects
				(font
					(size 1.27 1.27)
					(thickness 0.15)
				)
				(justify left bottom)
				(hide yes)
			)
		)
		(property "Description" "SMD Multilayer Ceramic Capacitor, 0.1 µF, 50 V, 0402 [1005 Metric], ± 10%, X5R, GRM Series"
			(at 99.06 82.55 0)
			(effects
				(font
					(size 1.27 1.27)
				)
				(hide yes)
			)
		)
		(property "Manufacturer" "Murata"
			(at 119.38 62.23 0)
			(effects
				(font
					(size 1.27 1.27)
					(thickness 0.15)
				)
				(justify left bottom)
				(hide yes)
			)
		)
		(property "MPN" "GRM155R61H104KE14D"
			(at 119.38 64.77 0)
			(effects
				(font
					(size 1.27 1.27)
					(thickness 0.15)
				)
				(justify left bottom)
				(hide yes)
			)
		)
		(property "Val" "100n"
			(at 95.758 81.534 0)
			(effects
				(font
					(size 1.27 1.27)
					(thickness 0.15)
				)
			)
		)
		(property "License" "Apache-2.0"
			(at 119.38 59.69 0)
			(effects
				(font
					(size 1.27 1.27)
					(thickness 0.15)
				)
				(justify left bottom)
				(hide yes)
			)
		)
		(property "Author" "Antmicro"
			(at 119.38 57.15 0)
			(effects
				(font
					(size 1.27 1.27)
					(thickness 0.15)
				)
				(justify left bottom)
				(hide yes)
			)
		)
		(property "Voltage" "50V"
			(at 119.38 54.61 0)
			(effects
				(font
					(size 1.27 1.27)
				)
				(justify left bottom)
				(hide yes)
			)
		)
		(property "Dielectric" "X5R"
			(at 119.38 52.07 0)
			(effects
				(font
					(size 1.27 1.27)
				)
				(justify left bottom)
				(hide yes)
			)
		)
		(pin "1"
		)
		(pin "2"
		)
		(instances
			(project "jetson-agx-thor-baseboard"
				(path ""
					(reference "C256")
					(unit 1)
				)
			)
		)
	)
	(symbol
		(lib_id "antmicropower:+5V")
		(at 148.59 254 0)
		(unit 1)
		(exclude_from_sim no)
		(in_bom yes)
		(on_board yes)
		(dnp no)
		(property "Reference" "#PWR0423"
			(at 148.59 257.81 0)
			(effects
				(font
					(size 1.27 1.27)
				)
				(justify left bottom)
				(hide yes)
			)
		)
		(property "Value" "+5V"
			(at 146.685 250.825 0)
			(effects
				(font
					(size 1.27 1.27)
					(thickness 0.15)
				)
				(justify left bottom)
			)
		)
		(property "Footprint" ""
			(at 163.83 261.62 0)
			(effects
				(font
					(size 1.27 1.27)
					(thickness 0.15)
				)
				(justify left bottom)
				(hide yes)
			)
		)
		(property "Datasheet" ""
			(at 163.83 264.16 0)
			(effects
				(font
					(size 1.27 1.27)
					(thickness 0.15)
				)
				(justify left bottom)
				(hide yes)
			)
		)
		(property "Description" ""
			(at 148.59 254 0)
			(effects
				(font
					(size 1.27 1.27)
				)
				(hide yes)
			)
		)
		(property "Author" "Antmicro"
			(at 163.83 261.62 0)
			(effects
				(font
					(size 1.27 1.27)
					(thickness 0.15)
				)
				(justify left bottom)
				(hide yes)
			)
		)
		(property "License" "Apache-2.0"
			(at 163.83 264.16 0)
			(effects
				(font
					(size 1.27 1.27)
					(thickness 0.15)
				)
				(justify left bottom)
				(hide yes)
			)
		)
		(pin "1"
		)
		(instances
			(project "jetson-agx-thor-baseboard"
				(path ""
					(reference "#PWR0423")
					(unit 1)
				)
			)
		)
	)
	(symbol
		(lib_id "antmicroDiodesRectifiersSingle:RB521S30T1G")
		(at 231.14 231.14 180)
		(unit 1)
		(exclude_from_sim no)
		(in_bom yes)
		(on_board yes)
		(dnp no)
		(property "Reference" "D59"
			(at 229.108 224.79 0)
			(effects
				(font
					(size 1.27 1.27)
				)
			)
		)
		(property "Value" "RB521S30T1G"
			(at 208.28 215.9 0)
			(effects
				(font
					(size 1.27 1.27)
					(thickness 0.15)
				)
				(justify left bottom)
				(hide yes)
			)
		)
		(property "Footprint" "antmicro-footprints:SOD-523"
			(at 208.28 220.98 0)
			(effects
				(font
					(size 1.27 1.27)
					(thickness 0.15)
				)
				(justify left bottom)
				(hide yes)
			)
		)
		(property "Datasheet" "https://www.onsemi.com/pdf/datasheet/rb521s30t1-d.pdf"
			(at 208.28 218.44 0)
			(effects
				(font
					(size 1.27 1.27)
					(thickness 0.15)
				)
				(justify left bottom)
				(hide yes)
			)
		)
		(property "Description" "Small Signal Schottky Diode, Single, 30 V, 200 mA, 500 mV, 1 A, 125 °C"
			(at 231.14 231.14 0)
			(effects
				(font
					(size 1.27 1.27)
				)
				(hide yes)
			)
		)
		(property "MPN" "RB521S30T1G"
			(at 229.108 227.33 0)
			(effects
				(font
					(size 1.27 1.27)
					(thickness 0.15)
				)
			)
		)
		(property "Manufacturer" "ON Semiconductor"
			(at 208.28 213.36 0)
			(effects
				(font
					(size 1.27 1.27)
					(thickness 0.15)
				)
				(justify left bottom)
				(hide yes)
			)
		)
		(property "Author" "Antmicro"
			(at 208.28 210.82 0)
			(effects
				(font
					(size 1.27 1.27)
					(thickness 0.15)
				)
				(justify left bottom)
				(hide yes)
			)
		)
		(property "License" "Apache-2.0"
			(at 208.28 208.28 0)
			(effects
				(font
					(size 1.27 1.27)
					(thickness 0.15)
				)
				(justify left bottom)
				(hide yes)
			)
		)
		(pin "1"
		)
		(pin "2"
		)
		(instances
			(project "jetson-agx-thor-baseboard"
				(path ""
					(reference "D59")
					(unit 1)
				)
			)
		)
	)
	(symbol
		(lib_id "antmicroResistors0402:R_0R_0402")
		(at 187.96 151.13 0)
		(unit 1)
		(exclude_from_sim no)
		(in_bom yes)
		(on_board yes)
		(dnp no)
		(property "Reference" "R46"
			(at 193.04 150.495 0)
			(effects
				(font
					(size 1.27 1.27)
				)
				(justify left bottom)
			)
		)
		(property "Value" "R_0R_0402"
			(at 208.28 163.83 0)
			(effects
				(font
					(size 1.27 1.27)
					(thickness 0.15)
				)
				(justify left bottom)
				(hide yes)
			)
		)
		(property "Footprint" "antmicro-footprints:R_0402_1005Metric"
			(at 208.28 166.37 0)
			(effects
				(font
					(size 1.27 1.27)
					(thickness 0.15)
				)
				(justify left bottom)
				(hide yes)
			)
		)
		(property "Datasheet" "https://industrial.panasonic.com/cdbs/www-data/pdf/RDA0000/AOA0000C301.pdf"
			(at 208.28 168.91 0)
			(effects
				(font
					(size 1.27 1.27)
					(thickness 0.15)
				)
				(justify left bottom)
				(hide yes)
			)
		)
		(property "Description" "SMD Chip Resistor, Jumper, 0 ohm, 100 mW, 0402 [1005 Metric], Thick Film, General Purpose"
			(at 187.96 151.13 0)
			(effects
				(font
					(size 1.27 1.27)
				)
				(hide yes)
			)
		)
		(property "Manufacturer" "Panasonic"
			(at 208.28 173.99 0)
			(effects
				(font
					(size 1.27 1.27)
					(thickness 0.15)
				)
				(justify left bottom)
				(hide yes)
			)
		)
		(property "MPN" "ERJ2GE0R00X"
			(at 208.28 171.45 0)
			(effects
				(font
					(size 1.27 1.27)
					(thickness 0.15)
				)
				(justify left bottom)
				(hide yes)
			)
		)
		(property "Val" "0R"
			(at 185.42 150.495 0)
			(effects
				(font
					(size 1.27 1.27)
					(thickness 0.15)
				)
				(justify left bottom)
			)
		)
		(property "License" "Apache-2.0"
			(at 208.28 176.53 0)
			(effects
				(font
					(size 1.27 1.27)
					(thickness 0.15)
				)
				(justify left bottom)
				(hide yes)
			)
		)
		(property "Author" "Antmicro"
			(at 208.28 179.07 0)
			(effects
				(font
					(size 1.27 1.27)
					(thickness 0.15)
				)
				(justify left bottom)
				(hide yes)
			)
		)
		(property "Tolerance" "~"
			(at 208.28 161.29 0)
			(effects
				(font
					(size 1.27 1.27)
				)
				(justify left bottom)
				(hide yes)
			)
		)
		(property "Current" "1A"
			(at 208.28 181.61 0)
			(effects
				(font
					(size 1.27 1.27)
					(thickness 0.15)
				)
				(justify left bottom)
				(hide yes)
			)
		)
		(pin "1"
		)
		(pin "2"
		)
		(instances
			(project "jetson-agx-thor-baseboard"
				(path ""
					(reference "R46")
					(unit 1)
				)
			)
		)
	)
	(symbol
		(lib_id "antmicropower:GND")
		(at 17.78 50.8 0)
		(mirror y)
		(unit 1)
		(exclude_from_sim no)
		(in_bom yes)
		(on_board yes)
		(dnp no)
		(property "Reference" "#PWR0164"
			(at 17.78 57.15 0)
			(effects
				(font
					(size 1.27 1.27)
				)
				(justify left bottom)
				(hide yes)
			)
		)
		(property "Value" "GND"
			(at 21.336 52.578 0)
			(effects
				(font
					(size 1.27 1.27)
					(thickness 0.15)
				)
			)
		)
		(property "Footprint" ""
			(at 8.89 58.42 0)
			(effects
				(font
					(size 1.27 1.27)
					(thickness 0.15)
				)
				(justify left bottom)
				(hide yes)
			)
		)
		(property "Datasheet" ""
			(at 8.89 63.5 0)
			(effects
				(font
					(size 1.27 1.27)
					(thickness 0.15)
				)
				(justify left bottom)
				(hide yes)
			)
		)
		(property "Description" ""
			(at 17.78 50.8 0)
			(effects
				(font
					(size 1.27 1.27)
				)
				(hide yes)
			)
		)
		(property "Author" "Antmicro"
			(at 8.89 58.42 0)
			(effects
				(font
					(size 1.27 1.27)
					(thickness 0.15)
				)
				(justify left bottom)
				(hide yes)
			)
		)
		(property "License" "Apache-2.0"
			(at 8.89 60.96 0)
			(effects
				(font
					(size 1.27 1.27)
					(thickness 0.15)
				)
				(justify left bottom)
				(hide yes)
			)
		)
		(pin "1"
		)
		(instances
			(project "jetson-agx-thor-baseboard"
				(path ""
					(reference "#PWR0164")
					(unit 1)
				)
			)
		)
	)
	(symbol
		(lib_id "antmicroResistors0402:R_11k_0402")
		(at 27.94 125.73 90)
		(unit 1)
		(exclude_from_sim no)
		(in_bom yes)
		(on_board yes)
		(dnp no)
		(fields_autoplaced yes)
		(property "Reference" "R66"
			(at 30.48 121.92 90)
			(effects
				(font
					(size 1.27 1.27)
					(thickness 0.15)
				)
				(justify right)
			)
		)
		(property "Value" "R_11k_0402"
			(at 40.64 105.41 0)
			(effects
				(font
					(size 1.27 1.27)
					(thickness 0.15)
				)
				(justify left bottom)
				(hide yes)
			)
		)
		(property "Footprint" "antmicro-footprints:R_0402_1005Metric"
			(at 43.18 105.41 0)
			(effects
				(font
					(size 1.27 1.27)
					(thickness 0.15)
				)
				(justify left bottom)
				(hide yes)
			)
		)
		(property "Datasheet" "https://www.bourns.com/docs/product-datasheets/cr.pdf"
			(at 45.72 105.41 0)
			(effects
				(font
					(size 1.27 1.27)
					(thickness 0.15)
				)
				(justify left bottom)
				(hide yes)
			)
		)
		(property "Description" "SMD Chip Resistor, 11 kohm, ± 1%, 62.5 mW, 0402 [1005 Metric], Thick Film, General Purpose"
			(at 58.42 105.41 0)
			(effects
				(font
					(size 1.27 1.27)
				)
				(justify left bottom)
				(hide yes)
			)
		)
		(property "MPN" "CR0402-FX-1102GLF"
			(at 48.26 105.41 0)
			(effects
				(font
					(size 1.27 1.27)
					(thickness 0.15)
				)
				(justify left bottom)
				(hide yes)
			)
		)
		(property "Manufacturer" "Bourns"
			(at 50.8 105.41 0)
			(effects
				(font
					(size 1.27 1.27)
					(thickness 0.15)
				)
				(justify left bottom)
				(hide yes)
			)
		)
		(property "License" "Apache-2.0"
			(at 53.34 105.41 0)
			(effects
				(font
					(size 1.27 1.27)
					(thickness 0.15)
				)
				(justify left bottom)
				(hide yes)
			)
		)
		(property "Author" "Antmicro"
			(at 55.88 105.41 0)
			(effects
				(font
					(size 1.27 1.27)
					(thickness 0.15)
				)
				(justify left bottom)
				(hide yes)
			)
		)
		(property "Val" "11k"
			(at 30.48 124.46 90)
			(effects
				(font
					(size 1.27 1.27)
					(thickness 0.15)
				)
				(justify right)
			)
		)
		(property "Tolerance" "1%"
			(at 38.1 105.41 0)
			(effects
				(font
					(size 1.27 1.27)
				)
				(justify left bottom)
				(hide yes)
			)
		)
		(pin "1"
		)
		(pin "2"
		)
		(instances
			(project ""
				(path ""
					(reference "R66")
					(unit 1)
				)
			)
		)
	)
	(symbol
		(lib_id "antmicroLEDIndicationDiscrete:LED_G_0603_LTST-C190GKT")
		(at 392.43 166.37 90)
		(unit 1)
		(exclude_from_sim no)
		(in_bom yes)
		(on_board yes)
		(dnp no)
		(fields_autoplaced yes)
		(property "Reference" "D49"
			(at 394.335 162.56 90)
			(effects
				(font
					(size 1.27 1.27)
				)
				(justify right)
			)
		)
		(property "Value" "LED_G_0603_LTST-C190GKT"
			(at 400.05 143.51 0)
			(effects
				(font
					(size 1.27 1.27)
					(thickness 0.15)
				)
				(justify left bottom)
				(hide yes)
			)
		)
		(property "Footprint" "antmicro-footprints:LED_0603_1608Metric_G"
			(at 402.59 143.51 0)
			(effects
				(font
					(size 1.27 1.27)
					(thickness 0.15)
				)
				(justify left bottom)
				(hide yes)
			)
		)
		(property "Datasheet" "https://media.digikey.com/pdf/Data%20Sheets/Lite-On%20PDFs/LTST-C190GKT.pdf"
			(at 405.13 143.51 0)
			(effects
				(font
					(size 1.27 1.27)
					(thickness 0.15)
				)
				(justify left bottom)
				(hide yes)
			)
		)
		(property "Description" "LED, Green, SMD, 0603, 20 mA, 2.1 V, 569 nm"
			(at 392.43 166.37 0)
			(effects
				(font
					(size 1.27 1.27)
				)
				(hide yes)
			)
		)
		(property "MPN" "LTST-C190GKT"
			(at 407.67 143.51 0)
			(effects
				(font
					(size 1.27 1.27)
					(thickness 0.15)
				)
				(justify left bottom)
				(hide yes)
			)
		)
		(property "Manufacturer" "Lite-On"
			(at 410.21 143.51 0)
			(effects
				(font
					(size 1.27 1.27)
					(thickness 0.15)
				)
				(justify left bottom)
				(hide yes)
			)
		)
		(property "Author" "Antmicro"
			(at 412.75 143.51 0)
			(effects
				(font
					(size 1.27 1.27)
					(thickness 0.15)
				)
				(justify left bottom)
				(hide yes)
			)
		)
		(property "License" "Apache-2.0"
			(at 415.29 143.51 0)
			(effects
				(font
					(size 1.27 1.27)
					(thickness 0.15)
				)
				(justify left bottom)
				(hide yes)
			)
		)
		(property "Color" "Green"
			(at 394.335 165.1 90)
			(effects
				(font
					(size 1.27 1.27)
				)
				(justify right)
			)
		)
		(pin "1"
		)
		(pin "2"
		)
		(instances
			(project "jetson-agx-thor-baseboard"
				(path ""
					(reference "D49")
					(unit 1)
				)
			)
		)
	)
	(symbol
		(lib_id "antmicroCapacitors0402:C_100n_0402")
		(at 285.75 226.06 180)
		(unit 1)
		(exclude_from_sim no)
		(in_bom yes)
		(on_board yes)
		(dnp no)
		(property "Reference" "C82"
			(at 289.56 224.028 0)
			(effects
				(font
					(size 1.27 1.27)
				)
				(justify left bottom)
			)
		)
		(property "Value" "C_100n_0402"
			(at 265.43 215.9 0)
			(effects
				(font
					(size 1.27 1.27)
					(thickness 0.15)
				)
				(justify left bottom)
				(hide yes)
			)
		)
		(property "Footprint" "antmicro-footprints:C_0402_1005Metric"
			(at 265.43 213.36 0)
			(effects
				(font
					(size 1.27 1.27)
					(thickness 0.15)
				)
				(justify left bottom)
				(hide yes)
			)
		)
		(property "Datasheet" "https://www.murata.com/products/productdetail?partno=GRM155R61H104KE14%23"
			(at 265.43 210.82 0)
			(effects
				(font
					(size 1.27 1.27)
					(thickness 0.15)
				)
				(justify left bottom)
				(hide yes)
			)
		)
		(property "Description" "SMD Multilayer Ceramic Capacitor, 0.1 µF, 50 V, 0402 [1005 Metric], ± 10%, X5R, GRM Series"
			(at 285.75 226.06 0)
			(effects
				(font
					(size 1.27 1.27)
				)
				(hide yes)
			)
		)
		(property "Manufacturer" "Murata"
			(at 265.43 205.74 0)
			(effects
				(font
					(size 1.27 1.27)
					(thickness 0.15)
				)
				(justify left bottom)
				(hide yes)
			)
		)
		(property "MPN" "GRM155R61H104KE14D"
			(at 265.43 208.28 0)
			(effects
				(font
					(size 1.27 1.27)
					(thickness 0.15)
				)
				(justify left bottom)
				(hide yes)
			)
		)
		(property "Val" "100n"
			(at 281.94 226.695 0)
			(effects
				(font
					(size 1.27 1.27)
					(thickness 0.15)
				)
				(justify left bottom)
			)
		)
		(property "License" "Apache-2.0"
			(at 265.43 203.2 0)
			(effects
				(font
					(size 1.27 1.27)
					(thickness 0.15)
				)
				(justify left bottom)
				(hide yes)
			)
		)
		(property "Author" "Antmicro"
			(at 265.43 200.66 0)
			(effects
				(font
					(size 1.27 1.27)
					(thickness 0.15)
				)
				(justify left bottom)
				(hide yes)
			)
		)
		(property "Voltage" "50V"
			(at 265.43 198.12 0)
			(effects
				(font
					(size 1.27 1.27)
				)
				(justify left bottom)
				(hide yes)
			)
		)
		(property "Dielectric" "X5R"
			(at 265.43 195.58 0)
			(effects
				(font
					(size 1.27 1.27)
				)
				(justify left bottom)
				(hide yes)
			)
		)
		(pin "1"
		)
		(pin "2"
		)
		(instances
			(project "jetson-agx-thor-baseboard"
				(path ""
					(reference "C82")
					(unit 1)
				)
			)
		)
	)
	(symbol
		(lib_id "antmicroTVSDiodes:TPD4E05U06QDQARQ1")
		(at 341.63 110.49 270)
		(unit 1)
		(exclude_from_sim no)
		(in_bom yes)
		(on_board yes)
		(dnp no)
		(property "Reference" "U24"
			(at 335.788 121.412 90)
			(effects
				(font
					(size 1.27 1.27)
				)
				(justify right)
			)
		)
		(property "Value" "TPD4E05U06QDQARQ1"
			(at 331.47 134.62 0)
			(effects
				(font
					(size 1.27 1.27)
					(thickness 0.15)
				)
				(justify left bottom)
				(hide yes)
			)
		)
		(property "Footprint" "antmicro-footprints:USON-10_2.5x1mm_P0.5mm"
			(at 336.55 134.62 0)
			(effects
				(font
					(size 1.27 1.27)
					(thickness 0.15)
				)
				(justify left bottom)
				(hide yes)
			)
		)
		(property "Datasheet" "https://www.ti.com/lit/ds/symlink/tpd4e05u06-q1.pdf?HQS=dis-mous-null-mousermode-dsf-pf-null-wwe&ts=1663591265741&ref_url=https%253A%252F%252Fwww.mouser.com%252F"
			(at 334.01 134.62 0)
			(effects
				(font
					(size 1.27 1.27)
					(thickness 0.15)
				)
				(justify left bottom)
				(hide yes)
			)
		)
		(property "Description" "TVS diode array, 12 kV, USON-10, 5.5 V, 0.5 pF"
			(at 341.63 110.49 0)
			(effects
				(font
					(size 1.27 1.27)
				)
				(hide yes)
			)
		)
		(property "Manufacturer" "Texas Instruments"
			(at 328.93 134.62 0)
			(effects
				(font
					(size 1.27 1.27)
					(thickness 0.15)
				)
				(justify left bottom)
				(hide yes)
			)
		)
		(property "MPN" "TPD4E05U06QDQARQ1"
			(at 344.424 124.206 90)
			(effects
				(font
					(size 1.27 1.27)
					(thickness 0.15)
				)
				(justify right)
			)
		)
		(property "Author" "Antmicro"
			(at 326.39 134.62 0)
			(effects
				(font
					(size 1.27 1.27)
					(thickness 0.15)
				)
				(justify left bottom)
				(hide yes)
			)
		)
		(property "License" "Apache-2.0"
			(at 323.85 134.62 0)
			(effects
				(font
					(size 1.27 1.27)
					(thickness 0.15)
				)
				(justify left bottom)
				(hide yes)
			)
		)
		(pin "1"
		)
		(pin "10"
		)
		(pin "2"
		)
		(pin "3"
		)
		(pin "4"
		)
		(pin "5"
		)
		(pin "6"
		)
		(pin "7"
		)
		(pin "8"
		)
		(pin "9"
		)
		(instances
			(project "jetson-agx-thor-baseboard"
				(path ""
					(reference "U24")
					(unit 1)
				)
			)
		)
	)
	(symbol
		(lib_id "antmicropower:GND")
		(at 228.6 196.85 0)
		(unit 1)
		(exclude_from_sim no)
		(in_bom yes)
		(on_board yes)
		(dnp no)
		(property "Reference" "#PWR0383"
			(at 228.6 203.2 0)
			(effects
				(font
					(size 1.27 1.27)
				)
				(justify left bottom)
				(hide yes)
			)
		)
		(property "Value" "GND"
			(at 228.6 200.66 0)
			(effects
				(font
					(size 1.27 1.27)
					(thickness 0.15)
				)
			)
		)
		(property "Footprint" ""
			(at 237.49 204.47 0)
			(effects
				(font
					(size 1.27 1.27)
					(thickness 0.15)
				)
				(justify left bottom)
				(hide yes)
			)
		)
		(property "Datasheet" ""
			(at 237.49 209.55 0)
			(effects
				(font
					(size 1.27 1.27)
					(thickness 0.15)
				)
				(justify left bottom)
				(hide yes)
			)
		)
		(property "Description" ""
			(at 228.6 196.85 0)
			(effects
				(font
					(size 1.27 1.27)
				)
				(hide yes)
			)
		)
		(property "Author" "Antmicro"
			(at 237.49 204.47 0)
			(effects
				(font
					(size 1.27 1.27)
					(thickness 0.15)
				)
				(justify left bottom)
				(hide yes)
			)
		)
		(property "License" "Apache-2.0"
			(at 237.49 207.01 0)
			(effects
				(font
					(size 1.27 1.27)
					(thickness 0.15)
				)
				(justify left bottom)
				(hide yes)
			)
		)
		(pin "1"
		)
		(instances
			(project "jetson-agx-thor-baseboard"
				(path ""
					(reference "#PWR0383")
					(unit 1)
				)
			)
		)
	)
	(symbol
		(lib_id "antmicroResistors0402:R_0R_0402")
		(at 116.84 139.7 0)
		(unit 1)
		(exclude_from_sim no)
		(in_bom no)
		(on_board yes)
		(dnp yes)
		(fields_autoplaced yes)
		(property "Reference" "R71"
			(at 116.84 139.065 0)
			(effects
				(font
					(size 1.27 1.27)
				)
				(justify right bottom)
			)
		)
		(property "Value" "R_0R_0402"
			(at 137.16 152.4 0)
			(effects
				(font
					(size 1.27 1.27)
					(thickness 0.15)
				)
				(justify left bottom)
				(hide yes)
			)
		)
		(property "Footprint" "antmicro-footprints:R_0402_1005Metric"
			(at 137.16 154.94 0)
			(effects
				(font
					(size 1.27 1.27)
					(thickness 0.15)
				)
				(justify left bottom)
				(hide yes)
			)
		)
		(property "Datasheet" "https://industrial.panasonic.com/cdbs/www-data/pdf/RDA0000/AOA0000C301.pdf"
			(at 137.16 157.48 0)
			(effects
				(font
					(size 1.27 1.27)
					(thickness 0.15)
				)
				(justify left bottom)
				(hide yes)
			)
		)
		(property "Description" "SMD Chip Resistor, Jumper, 0 ohm, 100 mW, 0402 [1005 Metric], Thick Film, General Purpose"
			(at 116.84 139.7 0)
			(effects
				(font
					(size 1.27 1.27)
				)
				(hide yes)
			)
		)
		(property "Manufacturer" "Panasonic"
			(at 137.16 162.56 0)
			(effects
				(font
					(size 1.27 1.27)
					(thickness 0.15)
				)
				(justify left bottom)
				(hide yes)
			)
		)
		(property "MPN" "ERJ2GE0R00X"
			(at 137.16 160.02 0)
			(effects
				(font
					(size 1.27 1.27)
					(thickness 0.15)
				)
				(justify left bottom)
				(hide yes)
			)
		)
		(property "Val" "0R"
			(at 124.46 139.065 0)
			(effects
				(font
					(size 1.27 1.27)
					(thickness 0.15)
				)
				(justify right bottom)
			)
		)
		(property "License" "Apache-2.0"
			(at 137.16 165.1 0)
			(effects
				(font
					(size 1.27 1.27)
					(thickness 0.15)
				)
				(justify left bottom)
				(hide yes)
			)
		)
		(property "Author" "Antmicro"
			(at 137.16 167.64 0)
			(effects
				(font
					(size 1.27 1.27)
					(thickness 0.15)
				)
				(justify left bottom)
				(hide yes)
			)
		)
		(property "Tolerance" "~"
			(at 137.16 149.86 0)
			(effects
				(font
					(size 1.27 1.27)
				)
				(justify left bottom)
				(hide yes)
			)
		)
		(property "Current" "1A"
			(at 137.16 170.18 0)
			(effects
				(font
					(size 1.27 1.27)
					(thickness 0.15)
				)
				(justify left bottom)
				(hide yes)
			)
		)
		(pin "1"
		)
		(pin "2"
		)
		(instances
			(project "jetson-agx-thor-baseboard"
				(path ""
					(reference "R71")
					(unit 1)
				)
			)
		)
	)
	(symbol
		(lib_id "antmicroCapacitors0402:C_100n_0402")
		(at 74.93 233.68 90)
		(unit 1)
		(exclude_from_sim no)
		(in_bom yes)
		(on_board yes)
		(dnp no)
		(fields_autoplaced yes)
		(property "Reference" "C111"
			(at 77.47 229.8636 90)
			(effects
				(font
					(size 1.27 1.27)
				)
				(justify right)
			)
		)
		(property "Value" "C_100n_0402"
			(at 85.09 213.36 0)
			(effects
				(font
					(size 1.27 1.27)
					(thickness 0.15)
				)
				(justify left bottom)
				(hide yes)
			)
		)
		(property "Footprint" "antmicro-footprints:C_0402_1005Metric"
			(at 87.63 213.36 0)
			(effects
				(font
					(size 1.27 1.27)
					(thickness 0.15)
				)
				(justify left bottom)
				(hide yes)
			)
		)
		(property "Datasheet" "https://www.murata.com/products/productdetail?partno=GRM155R61H104KE14%23"
			(at 90.17 213.36 0)
			(effects
				(font
					(size 1.27 1.27)
					(thickness 0.15)
				)
				(justify left bottom)
				(hide yes)
			)
		)
		(property "Description" "SMD Multilayer Ceramic Capacitor, 0.1 µF, 50 V, 0402 [1005 Metric], ± 10%, X5R, GRM Series"
			(at 74.93 233.68 0)
			(effects
				(font
					(size 1.27 1.27)
				)
				(hide yes)
			)
		)
		(property "Manufacturer" "Murata"
			(at 95.25 213.36 0)
			(effects
				(font
					(size 1.27 1.27)
					(thickness 0.15)
				)
				(justify left bottom)
				(hide yes)
			)
		)
		(property "MPN" "GRM155R61H104KE14D"
			(at 92.71 213.36 0)
			(effects
				(font
					(size 1.27 1.27)
					(thickness 0.15)
				)
				(justify left bottom)
				(hide yes)
			)
		)
		(property "Val" "100n"
			(at 77.47 232.4036 90)
			(effects
				(font
					(size 1.27 1.27)
					(thickness 0.15)
				)
				(justify right)
			)
		)
		(property "License" "Apache-2.0"
			(at 97.79 213.36 0)
			(effects
				(font
					(size 1.27 1.27)
					(thickness 0.15)
				)
				(justify left bottom)
				(hide yes)
			)
		)
		(property "Author" "Antmicro"
			(at 100.33 213.36 0)
			(effects
				(font
					(size 1.27 1.27)
					(thickness 0.15)
				)
				(justify left bottom)
				(hide yes)
			)
		)
		(property "Voltage" "50V"
			(at 102.87 213.36 0)
			(effects
				(font
					(size 1.27 1.27)
				)
				(justify left bottom)
				(hide yes)
			)
		)
		(property "Dielectric" "X5R"
			(at 105.41 213.36 0)
			(effects
				(font
					(size 1.27 1.27)
				)
				(justify left bottom)
				(hide yes)
			)
		)
		(pin "1"
		)
		(pin "2"
		)
		(instances
			(project "jetson-agx-thor-baseboard"
				(path ""
					(reference "C111")
					(unit 1)
				)
			)
		)
	)
	(symbol
		(lib_id "antmicropower:+3V3")
		(at 60.96 224.79 0)
		(mirror y)
		(unit 1)
		(exclude_from_sim no)
		(in_bom yes)
		(on_board yes)
		(dnp no)
		(fields_autoplaced yes)
		(property "Reference" "#PWR0200"
			(at 45.72 224.79 0)
			(effects
				(font
					(size 1.27 1.27)
					(thickness 0.15)
				)
				(justify left bottom)
				(hide yes)
			)
		)
		(property "Value" "+3V3"
			(at 60.96 219.71 0)
			(effects
				(font
					(size 1.27 1.27)
					(thickness 0.15)
				)
			)
		)
		(property "Footprint" ""
			(at 45.72 232.41 0)
			(effects
				(font
					(size 1.27 1.27)
					(thickness 0.15)
				)
				(justify left bottom)
				(hide yes)
			)
		)
		(property "Datasheet" ""
			(at 45.72 234.95 0)
			(effects
				(font
					(size 1.27 1.27)
					(thickness 0.15)
				)
				(justify left bottom)
				(hide yes)
			)
		)
		(property "Description" ""
			(at 60.96 224.79 0)
			(effects
				(font
					(size 1.27 1.27)
				)
				(hide yes)
			)
		)
		(property "Author" "Antmicro"
			(at 45.72 227.33 0)
			(effects
				(font
					(size 1.27 1.27)
					(thickness 0.15)
				)
				(justify left bottom)
				(hide yes)
			)
		)
		(property "License" "Apache-2.0"
			(at 45.72 229.87 0)
			(effects
				(font
					(size 1.27 1.27)
					(thickness 0.15)
				)
				(justify left bottom)
				(hide yes)
			)
		)
		(pin "1"
		)
		(instances
			(project "jetson-agx-thor-baseboard"
				(path ""
					(reference "#PWR0200")
					(unit 1)
				)
			)
		)
	)
)
